FILE_TYPE = MACRO_DRAWING;
SET COLOR_WIRE YELLOW;
SET COLOR_PROP MONO;
SET COLOR_DOT WHITE;
SET COLOR_ARC YELLOW;
SET COLOR_BODY GREEN;
SET COLOR_NOTE MONO;
SET PROP_DISPLAY VALUE;
SET PAGE_NUMBER P211;
FORCEADD RES..2
(-1600 4500);
FORCEPROP 1 LAST WATTAGE 1/16W
J 0
(-1560 4475);
DISPLAY 0.617021 (-1560 4475);
PAINT SKYBLUE (-1560 4475);
FORCEPROP 1 LAST MATERIAL CHIP
J 0
(-1560 4425);
DISPLAY 0.617021 (-1560 4425);
PAINT SKYBLUE (-1560 4425);
FORCEPROP 1 LAST VALUE 100.0
J 0
(-1555 4575);
DISPLAY 0.617021 (-1555 4575);
PAINT SKYBLUE (-1555 4575);
FORCEPROP 1 LASTPIN (-1600 4400) $PN 2
J 0
(-1595 4410);
DISPLAY 0.617021 (-1595 4410);
PAINT ORANGE (-1595 4410);
FORCEPROP 1 LASTPIN (-1600 4600) $PN 1
J 0
(-1595 4562);
DISPLAY 0.617021 (-1595 4562);
PAINT ORANGE (-1595 4562);
FORCEPROP 1 LAST TOLERANCE 1%
J 0
(-1555 4525);
DISPLAY 0.617021 (-1555 4525);
PAINT SKYBLUE (-1555 4525);
FORCEPROP 1 LAST LOCATION R3P13
J 0
(-1555 4625);
DISPLAY 0.617021 (-1555 4625);
PAINT AQUA (-1555 4625);
FORCEPROP 1 LAST PART_NUMBER G21796-017
J 0
(-1560 4375);
DISPLAY 0.617021 (-1560 4375);
PAINT BLUE (-1560 4375);
FORCEPROP 1 LAST PACK_TYPE 0402
J 0
(-1560 4325);
DISPLAY 0.617021 (-1560 4325);
PAINT SKYBLUE (-1560 4325);
FORCEPROP 0 LAST CDS_SEC 1
J 0
(-1550 4675);
PAINT MONO (-1550 4675);
DISPLAY INVISIBLE (-1550 4675);
FORCEPROP 2 LAST CDS_LIB mstr_discrete
J 0
(-1600 4500);
PAINT ORANGE (-1600 4500);
DISPLAY INVISIBLE (-1600 4500);
FORCEPROP 2 LAST ROOM PVCCIN_CPU0_VR
J 0
(-1550 4675);
DISPLAY 1.361702 (-1550 4675);
PAINT ORANGE (-1550 4675);
DISPLAY INVISIBLE (-1550 4675);
FORCEPROP 2 LAST SEC_TYPE 0402
J 0
(-1550 4725);
DISPLAY 1.021277 (-1550 4725);
PAINT ORANGE (-1550 4725);
DISPLAY INVISIBLE (-1550 4725);
FORCEPROP 2 LAST SEC 1
J 0
(-1550 4725);
DISPLAY 0.680851 (-1550 4725);
PAINT MONO (-1550 4725);
DISPLAY INVISIBLE (-1550 4725);
FORCEPROP 1 LAST PATH I100
J 0
(-1550 4675);
DISPLAY 0.978723 (-1550 4675);
PAINT WHITE (-1550 4675);
DISPLAY INVISIBLE (-1550 4675);
FORCEPROP 2 LAST CDS_LOCATION R3P13
J 0
(-1555 4625);
DISPLAY 0.617021 (-1555 4625);
PAINT AQUA (-1555 4625);
DISPLAY INVISIBLE (-1555 4625);
FORCEADD RES..2
(-575 1200);
FORCEPROP 1 LAST MATERIAL CHIP
J 0
(-535 1125);
DISPLAY 0.617021 (-535 1125);
PAINT SKYBLUE (-535 1125);
FORCEPROP 1 LAST TOLERANCE 1%
J 0
(-530 1225);
DISPLAY 0.617021 (-530 1225);
PAINT SKYBLUE (-530 1225);
FORCEPROP 1 LAST WATTAGE 1/16W
J 0
(-535 1175);
DISPLAY 0.617021 (-535 1175);
PAINT SKYBLUE (-535 1175);
FORCEPROP 1 LASTPIN (-575 1100) $PN 2
J 0
(-570 1110);
DISPLAY 0.617021 (-570 1110);
PAINT ORANGE (-570 1110);
FORCEPROP 1 LAST LOCATION R3N22
J 0
(-530 1325);
DISPLAY 0.617021 (-530 1325);
PAINT AQUA (-530 1325);
FORCEPROP 1 LASTPIN (-575 1300) $PN 1
J 0
(-570 1262);
DISPLAY 0.617021 (-570 1262);
PAINT ORANGE (-570 1262);
FORCEPROP 1 LAST VALUE 4.02K
J 0
(-530 1275);
DISPLAY 0.617021 (-530 1275);
PAINT SKYBLUE (-530 1275);
FORCEPROP 1 LAST PACK_TYPE 0402
J 0
(-535 1025);
DISPLAY 0.617021 (-535 1025);
PAINT SKYBLUE (-535 1025);
FORCEPROP 1 LAST PART_NUMBER G21796-082
J 0
(-535 1075);
DISPLAY 0.617021 (-535 1075);
PAINT BLUE (-535 1075);
FORCEPROP 2 LAST SEC_TYPE 0402
J 0
(-525 1425);
DISPLAY 1.021277 (-525 1425);
PAINT ORANGE (-525 1425);
DISPLAY INVISIBLE (-525 1425);
FORCEPROP 2 LAST SEC 1
J 0
(-525 1425);
PAINT MONO (-525 1425);
DISPLAY INVISIBLE (-525 1425);
FORCEPROP 0 LAST ROOM PVCCIN_CPU0_VR
J 0
(-525 1425);
DISPLAY 1.021277 (-525 1425);
PAINT ORANGE (-525 1425);
DISPLAY INVISIBLE (-525 1425);
FORCEPROP 2 LAST CDS_LIB mstr_discrete
J 0
(-575 1200);
PAINT ORANGE (-575 1200);
DISPLAY INVISIBLE (-575 1200);
FORCEPROP 1 LAST PATH I102
J 0
(-525 1375);
DISPLAY 0.978723 (-525 1375);
PAINT WHITE (-525 1375);
DISPLAY INVISIBLE (-525 1375);
FORCEPROP 2 LAST CDS_LOCATION R3N22
J 0
(-530 1325);
DISPLAY 0.617021 (-530 1325);
PAINT AQUA (-530 1325);
DISPLAY INVISIBLE (-530 1325);
FORCEADD CAP_A..1
(-2850 4300);
FORCEPROP 1 LAST MATERIAL X7R
J 0
(-2800 4250);
DISPLAY 0.617021 (-2800 4250);
PAINT SKYBLUE (-2800 4250);
FORCEPROP 1 LAST LOCATION C3P2
J 0
(-2800 4450);
DISPLAY 0.617021 (-2800 4450);
PAINT AQUA (-2800 4450);
FORCEPROP 1 LAST VALUE 0.1UF
J 0
(-2800 4400);
DISPLAY 0.617021 (-2800 4400);
PAINT SKYBLUE (-2800 4400);
FORCEPROP 1 LAST VOLTAGE 16V
J 0
(-2800 4350);
DISPLAY 0.617021 (-2800 4350);
PAINT SKYBLUE (-2800 4350);
FORCEPROP 1 LAST PART_NUMBER A36096-030
J 0
(-2800 4200);
DISPLAY 0.617021 (-2800 4200);
PAINT BLUE (-2800 4200);
FORCEPROP 1 LASTPIN (-2850 4400) $PN 1
J 0
(-2840 4380);
DISPLAY 0.787234 (-2840 4380);
PAINT ORANGE (-2840 4380);
FORCEPROP 1 LAST TOLERANCE 10%
J 0
(-2800 4300);
DISPLAY 0.617021 (-2800 4300);
PAINT SKYBLUE (-2800 4300);
FORCEPROP 1 LASTPIN (-2850 4200) $PN 2
J 0
(-2840 4180);
DISPLAY 0.787234 (-2840 4180);
PAINT ORANGE (-2840 4180);
FORCEPROP 1 LAST PACK_TYPE 0402V
J 0
(-2800 4150);
DISPLAY 0.617021 (-2800 4150);
PAINT SKYBLUE (-2800 4150);
FORCEPROP 0 LAST CDS_LOCATION C3P2
J 0
(-2800 4450);
PAINT MONO (-2800 4450);
DISPLAY INVISIBLE (-2800 4450);
FORCEPROP 2 LAST CDS_LIB dev_discrete
J 0
(-2850 4300);
PAINT MONO (-2850 4300);
DISPLAY INVISIBLE (-2850 4300);
FORCEPROP 0 LAST BOM_COST SM_THERM
J 0
(-2800 4450);
DISPLAY 1.021277 (-2800 4450);
PAINT ORANGE (-2800 4450);
DISPLAY INVISIBLE (-2800 4450);
FORCEPROP 0 LAST ROOM CPU_FANS
J 0
(-2800 4500);
DISPLAY 1.021277 (-2800 4500);
PAINT ORANGE (-2800 4500);
DISPLAY INVISIBLE (-2800 4500);
FORCEPROP 2 LAST SEC_TYPE 0402V
J 0
(-2800 4500);
DISPLAY 1.021277 (-2800 4500);
PAINT ORANGE (-2800 4500);
DISPLAY INVISIBLE (-2800 4500);
FORCEPROP 2 LAST SEC 1
J 0
(-2800 4500);
DISPLAY 0.680851 (-2800 4500);
PAINT MONO (-2800 4500);
DISPLAY INVISIBLE (-2800 4500);
FORCEPROP 0 LAST CDS_SEC 1
J 0
(-2800 4450);
PAINT MONO (-2800 4450);
DISPLAY INVISIBLE (-2800 4450);
FORCEPROP 1 LAST PATH I103
J 0
(-2800 4450);
DISPLAY 0.978723 (-2800 4450);
PAINT WHITE (-2800 4450);
DISPLAY INVISIBLE (-2800 4450);
FORCEADD CAP_A..1
(2475 1425);
FORCEPROP 1 LAST LOCATION C3P4
J 0
(2525 1525);
DISPLAY 0.617021 (2525 1525);
PAINT AQUA (2525 1525);
FORCEPROP 1 LAST PART_NUMBER D97712-004
J 0
(2525 1275);
DISPLAY 0.617021 (2525 1275);
PAINT BLUE (2525 1275);
FORCEPROP 1 LAST VALUE 1.0UF
J 0
(2525 1475);
DISPLAY 0.617021 (2525 1475);
PAINT SKYBLUE (2525 1475);
FORCEPROP 1 LAST TOLERANCE 10%
J 0
(2525 1375);
DISPLAY 0.617021 (2525 1375);
PAINT SKYBLUE (2525 1375);
FORCEPROP 1 LAST PACK_TYPE 0402V
J 0
(2525 1225);
DISPLAY 0.617021 (2525 1225);
PAINT SKYBLUE (2525 1225);
FORCEPROP 1 LAST VOLTAGE 6.3V
J 0
(2525 1425);
DISPLAY 0.617021 (2525 1425);
PAINT SKYBLUE (2525 1425);
FORCEPROP 1 LAST MATERIAL X6S
J 0
(2525 1325);
DISPLAY 0.617021 (2525 1325);
PAINT SKYBLUE (2525 1325);
FORCEPROP 1 LASTPIN (2475 1525) $PN 1
J 0
(2485 1505);
DISPLAY 0.617021 (2485 1505);
PAINT ORANGE (2485 1505);
FORCEPROP 1 LASTPIN (2475 1325) $PN 2
J 0
(2485 1305);
DISPLAY 0.617021 (2485 1305);
PAINT ORANGE (2485 1305);
FORCEPROP 2 LAST ROOM PVCCIO_CPU0
J 0
(2525 1575);
DISPLAY 1.361702 (2525 1575);
PAINT ORANGE (2525 1575);
DISPLAY INVISIBLE (2525 1575);
FORCEPROP 1 LAST PATH I11
J 0
(2525 1575);
DISPLAY 0.978723 (2525 1575);
PAINT WHITE (2525 1575);
DISPLAY INVISIBLE (2525 1575);
FORCEPROP 2 LAST SEC 1
J 0
(2525 1625);
DISPLAY 0.680851 (2525 1625);
PAINT MONO (2525 1625);
DISPLAY INVISIBLE (2525 1625);
FORCEPROP 2 LAST SEC_TYPE 0402V
J 0
(2525 1625);
DISPLAY 1.021277 (2525 1625);
PAINT ORANGE (2525 1625);
DISPLAY INVISIBLE (2525 1625);
FORCEPROP 2 LAST CDS_SEC 1
J 0
(2525 1575);
PAINT ORANGE (2525 1575);
DISPLAY INVISIBLE (2525 1575);
FORCEPROP 2 LAST CDS_LOCATION C3P4
J 0
(2525 1525);
DISPLAY 0.617021 (2525 1525);
PAINT AQUA (2525 1525);
DISPLAY INVISIBLE (2525 1525);
FORCEPROP 2 LAST CDS_LIB dev_discrete
J 0
(2475 1425);
PAINT ORANGE (2475 1425);
DISPLAY INVISIBLE (2475 1425);
FORCEADD GND..1
(2475 1100);
FORCEPROP 3 LASTPIN (2475 1150) SIG_NAME GND\g
J 0
(2485 1160);
DISPLAY 0.659574 (2485 1160);
PAINT MONO (2485 1160);
DISPLAY INVISIBLE (2485 1160);
FORCEPROP 1 LAST HDL_POWER GND
J 0
(2475 1250);
DISPLAY 1.170213 (2475 1250);
PAINT GREEN (2475 1250);
DISPLAY INVISIBLE (2475 1250);
FORCEPROP 1 LAST BODY_TYPE PLUMBING
J 0
(2430 1057);
DISPLAY 0.340426 (2430 1057);
PAINT GREEN (2430 1057);
DISPLAY INVISIBLE (2430 1057);
FORCEPROP 1 LAST VOLTAGE 0
J 0
(2475 1100);
PAINT SKYBLUE (2475 1100);
DISPLAY INVISIBLE (2475 1100);
FORCEPROP 1 LAST SIZE 1B
J 0
(2550 1050);
DISPLAY 1.170213 (2550 1050);
PAINT AQUA (2550 1050);
DISPLAY INVISIBLE (2550 1050);
FORCEPROP 2 LAST CDS_LIB mstr_symbols
J 0
(2475 1100);
PAINT ORANGE (2475 1100);
DISPLAY INVISIBLE (2475 1100);
FORCEPROP 1 LAST PATH I12
J 0
(2550 1100);
DISPLAY 0.872340 (2550 1100);
PAINT AQUA (2550 1100);
DISPLAY INVISIBLE (2550 1100);
FORCEPROP 2 LAST ROOM PVCCIO_CPU0
J 0
(1900 1175);
DISPLAY 1.361702 (1900 1175);
PAINT ORANGE (1900 1175);
DISPLAY INVISIBLE (1900 1175);
FORCEADD CAP_A..1
(2075 1425);
FORCEPROP 1 LAST PART_NUMBER A36096-030
J 0
(2125 1275);
DISPLAY 0.617021 (2125 1275);
PAINT BLUE (2125 1275);
FORCEPROP 1 LAST VALUE 0.1UF
J 0
(2125 1475);
DISPLAY 0.617021 (2125 1475);
PAINT SKYBLUE (2125 1475);
FORCEPROP 1 LAST VOLTAGE 16V
J 0
(2125 1425);
DISPLAY 0.617021 (2125 1425);
PAINT SKYBLUE (2125 1425);
FORCEPROP 1 LAST TOLERANCE 10%
J 0
(2125 1375);
DISPLAY 0.617021 (2125 1375);
PAINT SKYBLUE (2125 1375);
FORCEPROP 1 LAST PACK_TYPE 0402V
J 0
(2125 1225);
DISPLAY 0.617021 (2125 1225);
PAINT SKYBLUE (2125 1225);
FORCEPROP 1 LAST LOCATION C3P5
J 0
(2125 1525);
DISPLAY 0.617021 (2125 1525);
PAINT AQUA (2125 1525);
FORCEPROP 1 LAST MATERIAL X7R
J 0
(2125 1325);
DISPLAY 0.617021 (2125 1325);
PAINT SKYBLUE (2125 1325);
FORCEPROP 1 LASTPIN (2075 1525) $PN 1
J 0
(2085 1505);
DISPLAY 0.617021 (2085 1505);
PAINT ORANGE (2085 1505);
FORCEPROP 1 LASTPIN (2075 1325) $PN 2
J 0
(2085 1305);
DISPLAY 0.617021 (2085 1305);
PAINT ORANGE (2085 1305);
FORCEPROP 2 LAST SEC 1
J 0
(2125 1650);
DISPLAY 0.680851 (2125 1650);
PAINT MONO (2125 1650);
DISPLAY INVISIBLE (2125 1650);
FORCEPROP 2 LAST SEC_TYPE 0402V
J 0
(2125 1650);
DISPLAY 1.021277 (2125 1650);
PAINT ORANGE (2125 1650);
DISPLAY INVISIBLE (2125 1650);
FORCEPROP 2 LAST CDS_SEC 1
J 0
(2125 1575);
PAINT ORANGE (2125 1575);
DISPLAY INVISIBLE (2125 1575);
FORCEPROP 2 LAST ROOM PVCCIO_CPU0
J 0
(2125 1575);
DISPLAY 1.361702 (2125 1575);
PAINT ORANGE (2125 1575);
DISPLAY INVISIBLE (2125 1575);
FORCEPROP 1 LAST PATH I13
J 0
(2125 1575);
DISPLAY 0.978723 (2125 1575);
PAINT WHITE (2125 1575);
DISPLAY INVISIBLE (2125 1575);
FORCEPROP 2 LAST CDS_LOCATION C3P5
J 0
(2125 1525);
DISPLAY 0.617021 (2125 1525);
PAINT AQUA (2125 1525);
DISPLAY INVISIBLE (2125 1525);
FORCEPROP 2 LAST CDS_LIB dev_discrete
J 0
(2075 1425);
PAINT ORANGE (2075 1425);
DISPLAY INVISIBLE (2075 1425);
FORCEADD GND..1
(2075 1225);
FORCEPROP 3 LASTPIN (2075 1275) SIG_NAME GND\g
J 0
(2085 1285);
DISPLAY 0.659574 (2085 1285);
PAINT MONO (2085 1285);
DISPLAY INVISIBLE (2085 1285);
FORCEPROP 1 LAST HDL_POWER GND
J 0
(2075 1375);
DISPLAY 1.170213 (2075 1375);
PAINT GREEN (2075 1375);
DISPLAY INVISIBLE (2075 1375);
FORCEPROP 1 LAST BODY_TYPE PLUMBING
J 0
(2030 1182);
DISPLAY 0.340426 (2030 1182);
PAINT GREEN (2030 1182);
DISPLAY INVISIBLE (2030 1182);
FORCEPROP 2 LAST CDS_LIB mstr_symbols
J 0
(2075 1225);
PAINT ORANGE (2075 1225);
DISPLAY INVISIBLE (2075 1225);
FORCEPROP 1 LAST SIZE 1B
J 0
(2150 1175);
DISPLAY 1.170213 (2150 1175);
PAINT AQUA (2150 1175);
DISPLAY INVISIBLE (2150 1175);
FORCEPROP 1 LAST VOLTAGE 0
J 0
(2075 1225);
PAINT SKYBLUE (2075 1225);
DISPLAY INVISIBLE (2075 1225);
FORCEPROP 1 LAST PATH I14
J 0
(2150 1225);
DISPLAY 0.872340 (2150 1225);
PAINT AQUA (2150 1225);
DISPLAY INVISIBLE (2150 1225);
FORCEPROP 2 LAST ROOM PVCCIO_CPU0
J 0
(1500 1300);
DISPLAY 1.361702 (1500 1300);
PAINT ORANGE (1500 1300);
DISPLAY INVISIBLE (1500 1300);
FORCEADD OFFPAGE..2
R 2
(-2750 3000);
FORCEPROP 2 LAST $XR0 211 
J 0
(-3035 3000);
DISPLAY 0.638298 (-3035 3000);
PAINT MONO (-3035 3000);
FORCEPROP 2 LAST ROOM PVCCIO_CPU0
J 0
(-3300 3075);
DISPLAY 1.361702 (-3300 3075);
PAINT ORANGE (-3300 3075);
DISPLAY INVISIBLE (-3300 3075);
FORCEPROP 2 LAST CDS_LIB mstr_standard
J 0
(-2750 3000);
PAINT ORANGE (-2750 3000);
DISPLAY INVISIBLE (-2750 3000);
FORCEPROP 2 LAST PATH I15
J 0
(-2700 3075);
DISPLAY 1.021277 (-2700 3075);
PAINT ORANGE (-2700 3075);
DISPLAY INVISIBLE (-2700 3075);
FORCEPROP 1 LAST OFFPAGE TRUE
J 2
(-3075 2875);
DISPLAY 1.170213 (-3075 2875);
PAINT GREEN (-3075 2875);
DISPLAY INVISIBLE (-3075 2875);
FORCEPROP 1 LAST COMMENT_BODY TRUE
J 2
(-2705 2905);
DISPLAY 1.170213 (-2705 2905);
PAINT GREEN (-2705 2905);
DISPLAY INVISIBLE (-2705 2905);
FORCEADD RES..1
(-1250 2950);
FORCEPROP 1 LAST PART_NUMBER G21497-005
J 0
(-1400 2900);
DISPLAY 0.617021 (-1400 2900);
PAINT BLUE (-1400 2900);
FORCEPROP 1 LAST VALUE 0.0
J 2
(-1350 2850);
DISPLAY 0.617021 (-1350 2850);
PAINT SKYBLUE (-1350 2850);
FORCEPROP 1 LASTPIN (-1350 2950) $PN 1
J 0
(-1338 2962);
DISPLAY 0.617021 (-1338 2962);
PAINT ORANGE (-1338 2962);
FORCEPROP 1 LAST MATERIAL CHIP
J 0
(-1250 2800);
DISPLAY 0.617021 (-1250 2800);
PAINT SKYBLUE (-1250 2800);
FORCEPROP 1 LASTPIN (-1150 2950) $PN 2
J 0
(-1188 2962);
DISPLAY 0.617021 (-1188 2962);
PAINT ORANGE (-1188 2962);
FORCEPROP 1 LAST PACK_TYPE 0402
J 0
(-1175 2850);
DISPLAY 0.617021 (-1175 2850);
PAINT SKYBLUE (-1175 2850);
FORCEPROP 1 LAST LOCATION R3P11
J 0
(-1300 3000);
DISPLAY 0.617021 (-1300 3000);
PAINT AQUA (-1300 3000);
FORCEPROP 1 LAST TOLERANCE 5%
J 0
(-1300 2850);
DISPLAY 0.617021 (-1300 2850);
PAINT SKYBLUE (-1300 2850);
FORCEPROP 1 LAST WATTAGE 1/16W
J 2
(-1275 2800);
DISPLAY 0.617021 (-1275 2800);
PAINT SKYBLUE (-1275 2800);
FORCEPROP 2 LAST SEC_TYPE 0402
J 0
(-1300 3150);
DISPLAY 1.021277 (-1300 3150);
PAINT ORANGE (-1300 3150);
DISPLAY INVISIBLE (-1300 3150);
FORCEPROP 1 LAST PATH I16
J 0
(-1300 3100);
DISPLAY 0.978723 (-1300 3100);
PAINT WHITE (-1300 3100);
DISPLAY INVISIBLE (-1300 3100);
FORCEPROP 0 LAST SEC 1
J 0
(-1300 3050);
DISPLAY 0.680851 (-1300 3050);
PAINT MONO (-1300 3050);
DISPLAY INVISIBLE (-1300 3050);
FORCEPROP 2 LAST ROOM PVCCIO_CPU0
J 0
(-1300 3050);
DISPLAY 1.361702 (-1300 3050);
PAINT ORANGE (-1300 3050);
DISPLAY INVISIBLE (-1300 3050);
FORCEPROP 2 LAST CDS_LIB mstr_discrete
J 0
(-1250 2950);
PAINT ORANGE (-1250 2950);
DISPLAY INVISIBLE (-1250 2950);
FORCEPROP 2 LAST CDS_LOCATION R3P11
J 0
(-1300 3000);
DISPLAY 0.617021 (-1300 3000);
PAINT AQUA (-1300 3000);
DISPLAY INVISIBLE (-1300 3000);
FORCEADD PVCCIO_CPU0..1
(-1600 4825);
FORCEPROP 3 LASTPIN (-1600 4775) SIG_NAME PVCCIO_CPU0\g
J 0
(-1590 4785);
DISPLAY 0.659574 (-1590 4785);
PAINT MONO (-1590 4785);
DISPLAY INVISIBLE (-1590 4785);
FORCEPROP 1 LAST HDL_POWER PVCCIO_CPU0
J 1
(-1600 4875);
DISPLAY 0.872340 (-1600 4875);
PAINT GREEN (-1600 4875);
DISPLAY INVISIBLE (-1600 4875);
FORCEPROP 1 LAST BODY_TYPE PLUMBING
J 0
(-1645 4782);
DISPLAY 0.340426 (-1645 4782);
PAINT GREEN (-1645 4782);
DISPLAY INVISIBLE (-1645 4782);
FORCEPROP 1 LAST VOLTAGE 1.1V
J 0
(-1645 4782);
DISPLAY 0.340426 (-1645 4782);
PAINT SKYBLUE (-1645 4782);
DISPLAY INVISIBLE (-1645 4782);
FORCEPROP 2 LAST CDS_LIB mstr_symbols
J 0
(-1600 4825);
PAINT ORANGE (-1600 4825);
DISPLAY INVISIBLE (-1600 4825);
FORCEPROP 1 LAST PATH I18
J 0
(-1550 4850);
DISPLAY 0.872340 (-1550 4850);
PAINT AQUA (-1550 4850);
DISPLAY INVISIBLE (-1550 4850);
FORCEADD OFFPAGE..2
R 2
(-2750 2950);
FORCEPROP 2 LAST $XR2 201 
J 0
(-3244 2950);
DISPLAY 0.638298 (-3244 2950);
PAINT MONO (-3244 2950);
FORCEPROP 2 LAST $XR1 194 
J 0
(-3124 2950);
DISPLAY 0.638298 (-3124 2950);
PAINT MONO (-3124 2950);
FORCEPROP 2 LAST $XR0 21 
J 0
(-3004 2950);
DISPLAY 0.638298 (-3004 2950);
PAINT MONO (-3004 2950);
FORCEPROP 2 LAST ROOM PVCCIO_CPU0
J 0
(-3300 3025);
DISPLAY 1.361702 (-3300 3025);
PAINT ORANGE (-3300 3025);
DISPLAY INVISIBLE (-3300 3025);
FORCEPROP 2 LAST CDS_LIB mstr_standard
J 0
(-2750 2950);
PAINT ORANGE (-2750 2950);
DISPLAY INVISIBLE (-2750 2950);
FORCEPROP 2 LAST PATH I19
J 0
(-2700 3025);
DISPLAY 1.021277 (-2700 3025);
PAINT ORANGE (-2700 3025);
DISPLAY INVISIBLE (-2700 3025);
FORCEPROP 1 LAST OFFPAGE TRUE
J 2
(-3075 2825);
DISPLAY 1.170213 (-3075 2825);
PAINT GREEN (-3075 2825);
DISPLAY INVISIBLE (-3075 2825);
FORCEPROP 1 LAST COMMENT_BODY TRUE
J 2
(-2705 2855);
DISPLAY 1.170213 (-2705 2855);
PAINT GREEN (-2705 2855);
DISPLAY INVISIBLE (-2705 2855);
FORCEADD GND..1
(925 1900);
FORCEPROP 3 LASTPIN (925 1950) SIG_NAME GND\g
J 0
(935 1960);
DISPLAY 0.659574 (935 1960);
PAINT MONO (935 1960);
DISPLAY INVISIBLE (935 1960);
FORCEPROP 1 LAST HDL_POWER GND
J 0
(925 2050);
DISPLAY 1.170213 (925 2050);
PAINT GREEN (925 2050);
DISPLAY INVISIBLE (925 2050);
FORCEPROP 1 LAST BODY_TYPE PLUMBING
J 0
(880 1857);
DISPLAY 0.340426 (880 1857);
PAINT GREEN (880 1857);
DISPLAY INVISIBLE (880 1857);
FORCEPROP 1 LAST PATH I2
J 0
(1000 1900);
DISPLAY 0.872340 (1000 1900);
PAINT AQUA (1000 1900);
DISPLAY INVISIBLE (1000 1900);
FORCEPROP 2 LAST ROOM PVCCIO_CPU0
J 0
(350 1975);
DISPLAY 1.361702 (350 1975);
PAINT ORANGE (350 1975);
DISPLAY INVISIBLE (350 1975);
FORCEPROP 2 LAST CDS_LIB mstr_symbols
J 0
(925 1900);
PAINT ORANGE (925 1900);
DISPLAY INVISIBLE (925 1900);
FORCEPROP 1 LAST SIZE 1B
J 0
(1000 1850);
DISPLAY 1.170213 (1000 1850);
PAINT AQUA (1000 1850);
DISPLAY INVISIBLE (1000 1850);
FORCEPROP 1 LAST VOLTAGE 0
J 0
(925 1900);
PAINT SKYBLUE (925 1900);
DISPLAY INVISIBLE (925 1900);
FORCEADD CAP_A..1
(75 4175);
FORCEPROP 1 LAST VOLTAGE 6.3V
J 0
(125 4175);
DISPLAY 0.617021 (125 4175);
PAINT SKYBLUE (125 4175);
FORCEPROP 1 LAST TOLERANCE 10%
J 0
(125 4125);
DISPLAY 0.617021 (125 4125);
PAINT SKYBLUE (125 4125);
FORCEPROP 1 LAST MATERIAL X6S
J 0
(125 4075);
DISPLAY 0.617021 (125 4075);
PAINT SKYBLUE (125 4075);
FORCEPROP 1 LAST PART_NUMBER D97712-004
J 0
(125 4025);
DISPLAY 0.617021 (125 4025);
PAINT BLUE (125 4025);
FORCEPROP 1 LAST PACK_TYPE 0402V
J 0
(125 3975);
DISPLAY 0.617021 (125 3975);
PAINT SKYBLUE (125 3975);
FORCEPROP 1 LASTPIN (75 4275) $PN 1
J 0
(85 4255);
DISPLAY 0.787234 (85 4255);
PAINT ORANGE (85 4255);
FORCEPROP 1 LASTPIN (75 4075) $PN 2
J 0
(85 4055);
DISPLAY 0.787234 (85 4055);
PAINT ORANGE (85 4055);
FORCEPROP 1 LAST VALUE 1.0UF
J 0
(125 4225);
DISPLAY 0.617021 (125 4225);
PAINT SKYBLUE (125 4225);
FORCEPROP 1 LAST LOCATION C3P3
J 0
(125 4275);
DISPLAY 0.617021 (125 4275);
PAINT AQUA (125 4275);
FORCEPROP 2 LAST SEC_TYPE 0402V
J 0
(125 4375);
DISPLAY 1.021277 (125 4375);
PAINT ORANGE (125 4375);
DISPLAY INVISIBLE (125 4375);
FORCEPROP 2 LAST SEC 1
J 0
(125 4375);
DISPLAY 0.680851 (125 4375);
PAINT MONO (125 4375);
DISPLAY INVISIBLE (125 4375);
FORCEPROP 2 LAST ROOM PVCCIO_CPU0
J 0
(125 4325);
DISPLAY 1.361702 (125 4325);
PAINT ORANGE (125 4325);
DISPLAY INVISIBLE (125 4325);
FORCEPROP 1 LAST PATH I20
J 0
(125 4325);
DISPLAY 0.978723 (125 4325);
PAINT WHITE (125 4325);
DISPLAY INVISIBLE (125 4325);
FORCEPROP 2 LAST CDS_LOCATION C3P3
J 0
(125 4275);
DISPLAY 0.617021 (125 4275);
PAINT AQUA (125 4275);
DISPLAY INVISIBLE (125 4275);
FORCEPROP 2 LAST CDS_LIB dev_discrete
J 0
(75 4175);
PAINT ORANGE (75 4175);
DISPLAY INVISIBLE (75 4175);
FORCEADD GND..1
(75 3975);
FORCEPROP 3 LASTPIN (75 4025) SIG_NAME GND\g
J 0
(85 4035);
DISPLAY 0.659574 (85 4035);
PAINT MONO (85 4035);
DISPLAY INVISIBLE (85 4035);
FORCEPROP 1 LAST HDL_POWER GND
J 0
(75 4125);
DISPLAY 1.170213 (75 4125);
PAINT GREEN (75 4125);
DISPLAY INVISIBLE (75 4125);
FORCEPROP 1 LAST BODY_TYPE PLUMBING
J 0
(30 3932);
DISPLAY 0.340426 (30 3932);
PAINT GREEN (30 3932);
DISPLAY INVISIBLE (30 3932);
FORCEPROP 1 LAST SIZE 1B
J 0
(150 3925);
DISPLAY 1.170213 (150 3925);
PAINT AQUA (150 3925);
DISPLAY INVISIBLE (150 3925);
FORCEPROP 1 LAST PATH I21
J 0
(150 3975);
DISPLAY 0.872340 (150 3975);
PAINT AQUA (150 3975);
DISPLAY INVISIBLE (150 3975);
FORCEPROP 1 LAST VOLTAGE 0
J 0
(75 3975);
PAINT SKYBLUE (75 3975);
DISPLAY INVISIBLE (75 3975);
FORCEPROP 2 LAST CDS_LIB mstr_symbols
J 0
(75 3975);
PAINT ORANGE (75 3975);
DISPLAY INVISIBLE (75 3975);
FORCEPROP 2 LAST ROOM PVCCIO_CPU0
J 0
(-500 4050);
DISPLAY 1.361702 (-500 4050);
PAINT ORANGE (-500 4050);
DISPLAY INVISIBLE (-500 4050);
FORCEADD CAP_A..1
(-325 4175);
FORCEPROP 1 LAST TOLERANCE 10%
J 0
(-275 4125);
DISPLAY 0.617021 (-275 4125);
PAINT SKYBLUE (-275 4125);
FORCEPROP 1 LAST VOLTAGE 16V
J 0
(-275 4175);
DISPLAY 0.617021 (-275 4175);
PAINT SKYBLUE (-275 4175);
FORCEPROP 1 LAST MATERIAL X7R
J 0
(-275 4075);
DISPLAY 0.617021 (-275 4075);
PAINT SKYBLUE (-275 4075);
FORCEPROP 1 LAST PART_NUMBER A36096-030
J 0
(-275 4025);
DISPLAY 0.617021 (-275 4025);
PAINT BLUE (-275 4025);
FORCEPROP 1 LAST PACK_TYPE 0402V
J 0
(-275 3975);
DISPLAY 0.617021 (-275 3975);
PAINT SKYBLUE (-275 3975);
FORCEPROP 1 LAST LOCATION C3P7
J 0
(-275 4275);
DISPLAY 0.617021 (-275 4275);
PAINT AQUA (-275 4275);
FORCEPROP 1 LAST VALUE 0.1UF
J 0
(-275 4225);
DISPLAY 0.617021 (-275 4225);
PAINT SKYBLUE (-275 4225);
FORCEPROP 1 LASTPIN (-325 4275) $PN 1
J 0
(-315 4255);
DISPLAY 0.617021 (-315 4255);
PAINT ORANGE (-315 4255);
FORCEPROP 1 LASTPIN (-325 4075) $PN 2
J 0
(-315 4055);
DISPLAY 0.617021 (-315 4055);
PAINT ORANGE (-315 4055);
FORCEPROP 2 LAST SEC_TYPE 0402V
J 0
(-275 4375);
DISPLAY 1.021277 (-275 4375);
PAINT ORANGE (-275 4375);
DISPLAY INVISIBLE (-275 4375);
FORCEPROP 2 LAST SEC 1
J 0
(-275 4325);
DISPLAY 0.680851 (-275 4325);
PAINT MONO (-275 4325);
DISPLAY INVISIBLE (-275 4325);
FORCEPROP 2 LAST CDS_SEC 1
J 0
(-275 4325);
PAINT ORANGE (-275 4325);
DISPLAY INVISIBLE (-275 4325);
FORCEPROP 2 LAST ROOM PVCCIO_CPU0
J 0
(-275 4325);
DISPLAY 1.361702 (-275 4325);
PAINT ORANGE (-275 4325);
DISPLAY INVISIBLE (-275 4325);
FORCEPROP 1 LAST PATH I22
J 0
(-275 4325);
DISPLAY 0.978723 (-275 4325);
PAINT WHITE (-275 4325);
DISPLAY INVISIBLE (-275 4325);
FORCEPROP 2 LAST CDS_LOCATION C3P7
J 0
(-275 4275);
DISPLAY 0.617021 (-275 4275);
PAINT AQUA (-275 4275);
DISPLAY INVISIBLE (-275 4275);
FORCEPROP 2 LAST CDS_LIB dev_discrete
J 0
(-325 4175);
PAINT ORANGE (-325 4175);
DISPLAY INVISIBLE (-325 4175);
FORCEADD GND..1
(-325 3975);
FORCEPROP 3 LASTPIN (-325 4025) SIG_NAME GND\g
J 0
(-315 4035);
DISPLAY 0.659574 (-315 4035);
PAINT MONO (-315 4035);
DISPLAY INVISIBLE (-315 4035);
FORCEPROP 1 LAST HDL_POWER GND
J 0
(-325 4125);
DISPLAY 1.170213 (-325 4125);
PAINT GREEN (-325 4125);
DISPLAY INVISIBLE (-325 4125);
FORCEPROP 1 LAST BODY_TYPE PLUMBING
J 0
(-370 3932);
DISPLAY 0.340426 (-370 3932);
PAINT GREEN (-370 3932);
DISPLAY INVISIBLE (-370 3932);
FORCEPROP 2 LAST ROOM PVCCIO_CPU0
J 0
(-900 4050);
DISPLAY 1.361702 (-900 4050);
PAINT ORANGE (-900 4050);
DISPLAY INVISIBLE (-900 4050);
FORCEPROP 1 LAST SIZE 1B
J 0
(-250 3925);
DISPLAY 1.170213 (-250 3925);
PAINT AQUA (-250 3925);
DISPLAY INVISIBLE (-250 3925);
FORCEPROP 1 LAST PATH I23
J 0
(-250 3975);
DISPLAY 0.872340 (-250 3975);
PAINT AQUA (-250 3975);
DISPLAY INVISIBLE (-250 3975);
FORCEPROP 1 LAST VOLTAGE 0
J 0
(-325 3975);
PAINT SKYBLUE (-325 3975);
DISPLAY INVISIBLE (-325 3975);
FORCEPROP 2 LAST CDS_LIB mstr_symbols
J 0
(-325 3975);
PAINT ORANGE (-325 3975);
DISPLAY INVISIBLE (-325 3975);
FORCEADD RES..2
(-625 4525);
FORCEPROP 1 LAST LOCATION R3P22
J 0
(-580 4650);
DISPLAY 0.617021 (-580 4650);
PAINT AQUA (-580 4650);
FORCEPROP 1 LAST PART_NUMBER G21497-005
J 0
(-585 4400);
DISPLAY 0.617021 (-585 4400);
PAINT BLUE (-585 4400);
FORCEPROP 1 LAST VALUE 0.0
J 0
(-580 4600);
DISPLAY 0.617021 (-580 4600);
PAINT SKYBLUE (-580 4600);
FORCEPROP 1 LAST PACK_TYPE 0402
J 0
(-585 4350);
DISPLAY 0.617021 (-585 4350);
PAINT SKYBLUE (-585 4350);
FORCEPROP 1 LAST MATERIAL CHIP
J 0
(-585 4450);
DISPLAY 0.617021 (-585 4450);
PAINT SKYBLUE (-585 4450);
FORCEPROP 1 LAST WATTAGE 1/16W
J 0
(-585 4500);
DISPLAY 0.617021 (-585 4500);
PAINT SKYBLUE (-585 4500);
FORCEPROP 1 LAST TOLERANCE 5%
J 0
(-580 4550);
DISPLAY 0.617021 (-580 4550);
PAINT SKYBLUE (-580 4550);
FORCEPROP 1 LASTPIN (-625 4425) $PN 2
J 0
(-620 4435);
DISPLAY 0.617021 (-620 4435);
PAINT ORANGE (-620 4435);
FORCEPROP 1 LASTPIN (-625 4625) $PN 1
J 0
(-620 4587);
DISPLAY 0.617021 (-620 4587);
PAINT ORANGE (-620 4587);
FORCEPROP 2 LAST SEC_TYPE 0402
J 0
(-575 4750);
DISPLAY 1.021277 (-575 4750);
PAINT ORANGE (-575 4750);
DISPLAY INVISIBLE (-575 4750);
FORCEPROP 2 LAST ROOM PVCCIO_CPU0
J 0
(-575 4700);
DISPLAY 1.361702 (-575 4700);
PAINT ORANGE (-575 4700);
DISPLAY INVISIBLE (-575 4700);
FORCEPROP 1 LAST PATH I24
J 0
(-575 4700);
DISPLAY 0.978723 (-575 4700);
PAINT WHITE (-575 4700);
DISPLAY INVISIBLE (-575 4700);
FORCEPROP 0 LAST SEC 1
J 0
(-575 4700);
DISPLAY 0.680851 (-575 4700);
PAINT MONO (-575 4700);
DISPLAY INVISIBLE (-575 4700);
FORCEPROP 2 LAST CDS_LOCATION R3P22
J 0
(-580 4650);
DISPLAY 0.617021 (-580 4650);
PAINT AQUA (-580 4650);
DISPLAY INVISIBLE (-580 4650);
FORCEPROP 2 LAST CDS_LIB mstr_discrete
J 0
(-625 4525);
PAINT ORANGE (-625 4525);
DISPLAY INVISIBLE (-625 4525);
FORCEADD P3V3_STBY..1
(-625 4850);
FORCEPROP 3 LASTPIN (-625 4800) SIG_NAME P3V3_STBY\g
J 0
(-615 4810);
DISPLAY 0.659574 (-615 4810);
PAINT MONO (-615 4810);
DISPLAY INVISIBLE (-615 4810);
FORCEPROP 1 LAST HDL_POWER P3V3_STBY
J 0
(-925 4725);
DISPLAY 0.872340 (-925 4725);
PAINT ORANGE (-925 4725);
DISPLAY INVISIBLE (-925 4725);
FORCEPROP 1 LAST BODY_TYPE PLUMBING
J 0
(-670 4807);
DISPLAY 0.340426 (-670 4807);
PAINT GREEN (-670 4807);
DISPLAY INVISIBLE (-670 4807);
FORCEPROP 1 LAST SIZE 1B
J 0
(-580 4872);
DISPLAY 0.340426 (-580 4872);
PAINT GREEN (-580 4872);
DISPLAY INVISIBLE (-580 4872);
FORCEPROP 2 LAST CDS_LIB mstr_symbols
J 0
(-625 4850);
PAINT ORANGE (-625 4850);
DISPLAY INVISIBLE (-625 4850);
FORCEPROP 1 LAST PATH I25
J 0
(-580 4852);
DISPLAY 0.340426 (-580 4852);
PAINT GREEN (-580 4852);
DISPLAY INVISIBLE (-580 4852);
FORCEPROP 1 LAST VOLTAGE 3.3V
J 0
(-670 4807);
DISPLAY 0.340426 (-670 4807);
PAINT SKYBLUE (-670 4807);
DISPLAY INVISIBLE (-670 4807);
FORCEADD OFFPAGE..1
(-3025 3975);
FORCEPROP 2 LAST $XR2 201 
J 0
(-3516 3975);
DISPLAY 0.638298 (-3516 3975);
PAINT MONO (-3516 3975);
FORCEPROP 2 LAST $XR1 194 
J 0
(-3396 3975);
DISPLAY 0.638298 (-3396 3975);
PAINT MONO (-3396 3975);
FORCEPROP 2 LAST $XR0 21 
J 0
(-3276 3975);
DISPLAY 0.638298 (-3276 3975);
PAINT MONO (-3276 3975);
FORCEPROP 1 LAST COMMENT_BODY TRUE
J 0
(-2900 3875);
DISPLAY 1.170213 (-2900 3875);
PAINT GREEN (-2900 3875);
DISPLAY INVISIBLE (-2900 3875);
FORCEPROP 1 LAST OFFPAGE TRUE
J 0
(-2700 3850);
DISPLAY 1.170213 (-2700 3850);
PAINT GREEN (-2700 3850);
DISPLAY INVISIBLE (-2700 3850);
FORCEPROP 2 LAST ROOM PVCCIO_CPU0
J 0
(-3575 4050);
DISPLAY 1.361702 (-3575 4050);
PAINT ORANGE (-3575 4050);
DISPLAY INVISIBLE (-3575 4050);
FORCEPROP 2 LAST CDS_LIB mstr_standard
J 0
(-3025 3975);
PAINT ORANGE (-3025 3975);
DISPLAY INVISIBLE (-3025 3975);
FORCEPROP 2 LAST PATH I26
J 0
(-3225 4025);
DISPLAY 1.021277 (-3225 4025);
PAINT ORANGE (-3225 4025);
DISPLAY INVISIBLE (-3225 4025);
FORCEADD PVCCIO_CPU0..1
(-2125 4875);
FORCEPROP 3 LASTPIN (-2125 4825) SIG_NAME PVCCIO_CPU0\g
J 0
(-2115 4835);
DISPLAY 0.659574 (-2115 4835);
PAINT MONO (-2115 4835);
DISPLAY INVISIBLE (-2115 4835);
FORCEPROP 1 LAST HDL_POWER PVCCIO_CPU0
J 1
(-2125 4925);
DISPLAY 0.872340 (-2125 4925);
PAINT GREEN (-2125 4925);
DISPLAY INVISIBLE (-2125 4925);
FORCEPROP 1 LAST BODY_TYPE PLUMBING
J 0
(-2170 4832);
DISPLAY 0.340426 (-2170 4832);
PAINT GREEN (-2170 4832);
DISPLAY INVISIBLE (-2170 4832);
FORCEPROP 2 LAST CDS_LIB mstr_symbols
J 0
(-2125 4875);
PAINT ORANGE (-2125 4875);
DISPLAY INVISIBLE (-2125 4875);
FORCEPROP 1 LAST PATH I27
J 0
(-2075 4900);
DISPLAY 0.872340 (-2075 4900);
PAINT AQUA (-2075 4900);
DISPLAY INVISIBLE (-2075 4900);
FORCEPROP 1 LAST VOLTAGE 1.1V
J 0
(-2170 4832);
DISPLAY 0.340426 (-2170 4832);
PAINT SKYBLUE (-2170 4832);
DISPLAY INVISIBLE (-2170 4832);
FORCEADD RES..1
(-1975 3975);
FORCEPROP 1 LAST PACK_TYPE 0402
J 0
(-1800 4050);
DISPLAY 0.617021 (-1800 4050);
PAINT SKYBLUE (-1800 4050);
FORCEPROP 1 LASTPIN (-1875 3975) $PN 2
J 0
(-1913 3987);
DISPLAY 0.617021 (-1913 3987);
PAINT ORANGE (-1913 3987);
FORCEPROP 1 LASTPIN (-2075 3975) $PN 1
J 0
(-2063 3987);
DISPLAY 0.617021 (-2063 3987);
PAINT ORANGE (-2063 3987);
FORCEPROP 1 LAST WATTAGE 1/16W
J 2
(-1925 4000);
DISPLAY 0.617021 (-1925 4000);
PAINT SKYBLUE (-1925 4000);
FORCEPROP 1 LAST LOCATION R3P15
J 0
(-2075 4150);
DISPLAY 0.617021 (-2075 4150);
PAINT AQUA (-2075 4150);
FORCEPROP 1 LAST TOLERANCE 1%
J 0
(-1925 4050);
DISPLAY 0.617021 (-1925 4050);
PAINT SKYBLUE (-1925 4050);
FORCEPROP 1 LAST MATERIAL CHIP
J 0
(-1875 4000);
DISPLAY 0.617021 (-1875 4000);
PAINT SKYBLUE (-1875 4000);
FORCEPROP 1 LAST VALUE 150.0
J 2
(-1975 4050);
DISPLAY 0.617021 (-1975 4050);
PAINT SKYBLUE (-1975 4050);
FORCEPROP 1 LAST PART_NUMBER G21796-009
J 0
(-2075 4100);
DISPLAY 0.617021 (-2075 4100);
PAINT BLUE (-2075 4100);
FORCEPROP 2 LAST SEC_TYPE 0402
J 0
(-2025 4200);
DISPLAY 1.021277 (-2025 4200);
PAINT ORANGE (-2025 4200);
DISPLAY INVISIBLE (-2025 4200);
FORCEPROP 2 LAST SEC 1
J 0
(-2025 4200);
DISPLAY 0.680851 (-2025 4200);
PAINT MONO (-2025 4200);
DISPLAY INVISIBLE (-2025 4200);
FORCEPROP 1 LAST PATH I29
J 0
(-2025 4125);
DISPLAY 0.978723 (-2025 4125);
PAINT WHITE (-2025 4125);
DISPLAY INVISIBLE (-2025 4125);
FORCEPROP 2 LAST CDS_LOCATION R3P15
J 0
(-2075 4150);
DISPLAY 0.617021 (-2075 4150);
PAINT AQUA (-2075 4150);
DISPLAY INVISIBLE (-2075 4150);
FORCEPROP 2 LAST ROOM PVCCIO_CPU0
J 0
(-2075 4200);
DISPLAY 1.361702 (-2075 4200);
PAINT ORANGE (-2075 4200);
DISPLAY INVISIBLE (-2075 4200);
FORCEPROP 2 LAST CDS_LIB mstr_discrete
J 0
(-1975 3975);
PAINT ORANGE (-1975 3975);
DISPLAY INVISIBLE (-1975 3975);
FORCEADD OFFPAGE..2
(2700 3000);
FORCEPROP 2 LAST $XR0 212 
J 0
(2889 3000);
DISPLAY 0.638298 (2889 3000);
PAINT MONO (2889 3000);
FORCEPROP 1 LAST COMMENT_BODY TRUE
J 0
(2655 2905);
DISPLAY 1.170213 (2655 2905);
PAINT GREEN (2655 2905);
DISPLAY INVISIBLE (2655 2905);
FORCEPROP 1 LAST OFFPAGE TRUE
J 0
(3025 2875);
DISPLAY 1.170213 (3025 2875);
PAINT GREEN (3025 2875);
DISPLAY INVISIBLE (3025 2875);
FORCEPROP 2 LAST PATH I3
J 0
(2875 3075);
DISPLAY 1.021277 (2875 3075);
PAINT ORANGE (2875 3075);
DISPLAY INVISIBLE (2875 3075);
FORCEPROP 2 LAST ROOM PVCCIO_CPU0
J 0
(2275 3075);
DISPLAY 1.361702 (2275 3075);
PAINT ORANGE (2275 3075);
DISPLAY INVISIBLE (2275 3075);
FORCEPROP 2 LAST CDS_LIB mstr_standard
J 0
(2700 3000);
PAINT ORANGE (2700 3000);
DISPLAY INVISIBLE (2700 3000);
FORCEADD VCC_CORE..1
(-2500 4850);
FORCEPROP 3 LASTPIN (-2500 4800) SIG_NAME VR_FET_SW_P12V_STBY_PVCCIO_CPU0\g
J 0
(-2490 4810);
DISPLAY 0.659574 (-2490 4810);
PAINT MONO (-2490 4810);
DISPLAY INVISIBLE (-2490 4810);
FORCEPROP 1 LAST HDL_POWER VR_FET_SW_P12V_STBY_PVCCIO_CPU0
J 1
(-2775 4900);
DISPLAY 0.617021 (-2775 4900);
PAINT GREEN (-2775 4900);
FORCEPROP 1 LAST PATH I30
J 0
(-2450 4875);
DISPLAY 0.872340 (-2450 4875);
PAINT AQUA (-2450 4875);
DISPLAY INVISIBLE (-2450 4875);
FORCEPROP 2 LAST CDS_LIB mstr_symbols
J 0
(-2500 4850);
PAINT ORANGE (-2500 4850);
DISPLAY INVISIBLE (-2500 4850);
FORCEADD RES..2
(-2500 4650);
FORCEPROP 1 LAST PART_NUMBER G21796-160
J 0
(-2485 4525);
DISPLAY 0.617021 (-2485 4525);
PAINT BLUE (-2485 4525);
FORCEPROP 1 LAST MATERIAL CHIP
J 0
(-2460 4575);
DISPLAY 0.617021 (-2460 4575);
PAINT SKYBLUE (-2460 4575);
FORCEPROP 1 LAST WATTAGE 1/16W
J 0
(-2460 4625);
DISPLAY 0.617021 (-2460 4625);
PAINT SKYBLUE (-2460 4625);
FORCEPROP 1 LAST LOCATION R3P12
J 0
(-2680 4650);
DISPLAY 0.617021 (-2680 4650);
PAINT AQUA (-2680 4650);
FORCEPROP 1 LAST VALUE 100.0K
J 0
(-2455 4725);
DISPLAY 0.617021 (-2455 4725);
PAINT SKYBLUE (-2455 4725);
FORCEPROP 1 LASTPIN (-2500 4750) $PN 1
J 0
(-2495 4712);
DISPLAY 0.617021 (-2495 4712);
PAINT ORANGE (-2495 4712);
FORCEPROP 1 LAST PACK_TYPE 0402
J 0
(-2460 4475);
DISPLAY 0.617021 (-2460 4475);
PAINT SKYBLUE (-2460 4475);
FORCEPROP 1 LAST TOLERANCE 1%
J 0
(-2455 4675);
DISPLAY 0.617021 (-2455 4675);
PAINT SKYBLUE (-2455 4675);
FORCEPROP 1 LASTPIN (-2500 4550) $PN 2
J 0
(-2495 4560);
DISPLAY 0.617021 (-2495 4560);
PAINT ORANGE (-2495 4560);
FORCEPROP 2 LAST SEC_TYPE 0402
J 0
(-2450 4875);
DISPLAY 1.021277 (-2450 4875);
PAINT ORANGE (-2450 4875);
DISPLAY INVISIBLE (-2450 4875);
FORCEPROP 2 LAST SEC 1
J 0
(-2450 4875);
DISPLAY 0.680851 (-2450 4875);
PAINT MONO (-2450 4875);
DISPLAY INVISIBLE (-2450 4875);
FORCEPROP 2 LAST NO_XNET_CONNECTION 1
J 0
(-2450 4875);
PAINT MONO (-2450 4875);
DISPLAY INVISIBLE (-2450 4875);
FORCEPROP 1 LAST PATH I31
J 0
(-2450 4825);
DISPLAY 0.978723 (-2450 4825);
PAINT WHITE (-2450 4825);
DISPLAY INVISIBLE (-2450 4825);
FORCEPROP 2 LAST ROOM PVCCIO_CPU0
J 0
(-2450 4825);
DISPLAY 1.361702 (-2450 4825);
PAINT ORANGE (-2450 4825);
DISPLAY INVISIBLE (-2450 4825);
FORCEPROP 2 LAST CDS_LIB mstr_discrete
J 0
(-2500 4650);
PAINT ORANGE (-2500 4650);
DISPLAY INVISIBLE (-2500 4650);
FORCEPROP 2 LAST CDS_LOCATION R3P12
J 0
(-2680 4650);
DISPLAY 0.617021 (-2680 4650);
PAINT AQUA (-2680 4650);
DISPLAY INVISIBLE (-2680 4650);
FORCEADD RES..2
(-2500 4300);
FORCEPROP 1 LAST WATTAGE 1/16W
J 0
(-2460 4275);
DISPLAY 0.617021 (-2460 4275);
PAINT SKYBLUE (-2460 4275);
FORCEPROP 1 LASTPIN (-2500 4400) $PN 1
J 0
(-2495 4362);
DISPLAY 0.617021 (-2495 4362);
PAINT ORANGE (-2495 4362);
FORCEPROP 1 LAST VALUE 1.5K
J 0
(-2455 4375);
DISPLAY 0.617021 (-2455 4375);
PAINT SKYBLUE (-2455 4375);
FORCEPROP 1 LAST LOCATION R3P16
J 0
(-2455 4425);
DISPLAY 0.617021 (-2455 4425);
PAINT AQUA (-2455 4425);
FORCEPROP 1 LASTPIN (-2500 4200) $PN 2
J 0
(-2495 4210);
DISPLAY 0.617021 (-2495 4210);
PAINT ORANGE (-2495 4210);
FORCEPROP 1 LAST PACK_TYPE 0402
J 0
(-2460 4125);
DISPLAY 0.617021 (-2460 4125);
PAINT SKYBLUE (-2460 4125);
FORCEPROP 1 LAST MATERIAL CHIP
J 0
(-2460 4225);
DISPLAY 0.617021 (-2460 4225);
PAINT SKYBLUE (-2460 4225);
FORCEPROP 1 LAST TOLERANCE 1%
J 0
(-2455 4325);
DISPLAY 0.617021 (-2455 4325);
PAINT SKYBLUE (-2455 4325);
FORCEPROP 1 LAST PART_NUMBER G21796-003
J 0
(-2460 4175);
DISPLAY 0.617021 (-2460 4175);
PAINT BLUE (-2460 4175);
FORCEPROP 2 LAST SEC_TYPE 0402
J 0
(-2450 4525);
DISPLAY 1.021277 (-2450 4525);
PAINT ORANGE (-2450 4525);
DISPLAY INVISIBLE (-2450 4525);
FORCEPROP 2 LAST SEC 1
J 0
(-2450 4525);
DISPLAY 0.680851 (-2450 4525);
PAINT MONO (-2450 4525);
DISPLAY INVISIBLE (-2450 4525);
FORCEPROP 1 LAST PATH I32
J 0
(-2450 4475);
DISPLAY 0.978723 (-2450 4475);
PAINT WHITE (-2450 4475);
DISPLAY INVISIBLE (-2450 4475);
FORCEPROP 2 LAST ROOM PVCCIO_CPU0
J 0
(-2450 4475);
DISPLAY 1.361702 (-2450 4475);
PAINT ORANGE (-2450 4475);
DISPLAY INVISIBLE (-2450 4475);
FORCEPROP 2 LAST CDS_LIB mstr_discrete
J 0
(-2500 4300);
PAINT ORANGE (-2500 4300);
DISPLAY INVISIBLE (-2500 4300);
FORCEPROP 2 LAST CDS_LOCATION R3P16
J 0
(-2655 4275);
DISPLAY 0.617021 (-2655 4275);
PAINT AQUA (-2655 4275);
DISPLAY INVISIBLE (-2655 4275);
FORCEADD GND..1
(-2500 4100);
FORCEPROP 3 LASTPIN (-2500 4150) SIG_NAME GND\g
J 0
(-2490 4160);
DISPLAY 0.659574 (-2490 4160);
PAINT MONO (-2490 4160);
DISPLAY INVISIBLE (-2490 4160);
FORCEPROP 1 LAST HDL_POWER GND
J 0
(-2500 4250);
DISPLAY 1.170213 (-2500 4250);
PAINT GREEN (-2500 4250);
DISPLAY INVISIBLE (-2500 4250);
FORCEPROP 1 LAST BODY_TYPE PLUMBING
J 0
(-2545 4057);
DISPLAY 0.340426 (-2545 4057);
PAINT GREEN (-2545 4057);
DISPLAY INVISIBLE (-2545 4057);
FORCEPROP 1 LAST PATH I34
J 0
(-2425 4100);
DISPLAY 0.872340 (-2425 4100);
PAINT AQUA (-2425 4100);
DISPLAY INVISIBLE (-2425 4100);
FORCEPROP 1 LAST VOLTAGE 0
J 0
(-2500 4100);
PAINT SKYBLUE (-2500 4100);
DISPLAY INVISIBLE (-2500 4100);
FORCEPROP 2 LAST CDS_LIB mstr_symbols
J 0
(-2500 4100);
PAINT ORANGE (-2500 4100);
DISPLAY INVISIBLE (-2500 4100);
FORCEPROP 2 LAST ROOM PVCCIO_CPU0
J 0
(-3075 4175);
DISPLAY 1.361702 (-3075 4175);
PAINT ORANGE (-3075 4175);
DISPLAY INVISIBLE (-3075 4175);
FORCEPROP 1 LAST SIZE 1B
J 0
(-2425 4050);
DISPLAY 1.170213 (-2425 4050);
PAINT AQUA (-2425 4050);
DISPLAY INVISIBLE (-2425 4050);
FORCEADD GND..1
(-2850 4100);
FORCEPROP 3 LASTPIN (-2850 4150) SIG_NAME GND\g
J 0
(-2840 4160);
DISPLAY 0.659574 (-2840 4160);
PAINT MONO (-2840 4160);
DISPLAY INVISIBLE (-2840 4160);
FORCEPROP 1 LAST SIZE 1B
J 0
(-2775 4050);
DISPLAY 1.170213 (-2775 4050);
PAINT AQUA (-2775 4050);
DISPLAY INVISIBLE (-2775 4050);
FORCEPROP 1 LAST PATH I35
J 0
(-2775 4100);
DISPLAY 0.872340 (-2775 4100);
PAINT AQUA (-2775 4100);
DISPLAY INVISIBLE (-2775 4100);
FORCEPROP 2 LAST CDS_LIB mstr_symbols
J 0
(-2850 4100);
PAINT ORANGE (-2850 4100);
DISPLAY INVISIBLE (-2850 4100);
FORCEPROP 1 LAST VOLTAGE 0
J 0
(-2850 4100);
PAINT SKYBLUE (-2850 4100);
DISPLAY INVISIBLE (-2850 4100);
FORCEPROP 2 LAST ROOM PVCCIO_CPU0
J 0
(-3425 4175);
DISPLAY 1.361702 (-3425 4175);
PAINT ORANGE (-3425 4175);
DISPLAY INVISIBLE (-3425 4175);
FORCEPROP 1 LAST BODY_TYPE PLUMBING
J 0
(-2895 4057);
DISPLAY 0.340426 (-2895 4057);
PAINT GREEN (-2895 4057);
DISPLAY INVISIBLE (-2895 4057);
FORCEPROP 1 LAST HDL_POWER GND
J 0
(-2850 4250);
DISPLAY 1.170213 (-2850 4250);
PAINT GREEN (-2850 4250);
DISPLAY INVISIBLE (-2850 4250);
FORCEADD OFFPAGE..2
R 2
(-3325 4700);
FORCEPROP 2 LAST $XR0 211 
J 0
(-3610 4700);
DISPLAY 0.638298 (-3610 4700);
PAINT MONO (-3610 4700);
FORCEPROP 2 LAST ROOM PVCCIO_CPU0
J 0
(-3875 4775);
DISPLAY 1.361702 (-3875 4775);
PAINT ORANGE (-3875 4775);
DISPLAY INVISIBLE (-3875 4775);
FORCEPROP 2 LAST PATH I36
J 0
(-3575 4750);
DISPLAY 1.021277 (-3575 4750);
PAINT ORANGE (-3575 4750);
DISPLAY INVISIBLE (-3575 4750);
FORCEPROP 2 LAST CDS_LIB mstr_standard
J 2
(-3325 4700);
PAINT ORANGE (-3325 4700);
DISPLAY INVISIBLE (-3325 4700);
FORCEPROP 1 LAST OFFPAGE TRUE
J 2
(-3650 4575);
DISPLAY 1.170213 (-3650 4575);
PAINT GREEN (-3650 4575);
DISPLAY INVISIBLE (-3650 4575);
FORCEPROP 1 LAST COMMENT_BODY TRUE
J 2
(-3280 4605);
DISPLAY 1.170213 (-3280 4605);
PAINT GREEN (-3280 4605);
DISPLAY INVISIBLE (-3280 4605);
FORCEADD OFFPAGE..1
(-2750 3150);
FORCEPROP 2 LAST $XR0 211 
J 0
(-3002 3150);
DISPLAY 0.638298 (-3002 3150);
PAINT MONO (-3002 3150);
FORCEPROP 2 LAST ROOM PVCCIO_CPU0
J 0
(-3300 3225);
DISPLAY 1.361702 (-3300 3225);
PAINT ORANGE (-3300 3225);
DISPLAY INVISIBLE (-3300 3225);
FORCEPROP 2 LAST CDS_LIB mstr_standard
J 0
(-2750 3150);
PAINT ORANGE (-2750 3150);
DISPLAY INVISIBLE (-2750 3150);
FORCEPROP 2 LAST PATH I37
J 0
(-2700 3225);
DISPLAY 1.021277 (-2700 3225);
PAINT ORANGE (-2700 3225);
DISPLAY INVISIBLE (-2700 3225);
FORCEPROP 1 LAST OFFPAGE TRUE
J 0
(-2425 3025);
DISPLAY 1.170213 (-2425 3025);
PAINT GREEN (-2425 3025);
DISPLAY INVISIBLE (-2425 3025);
FORCEPROP 1 LAST COMMENT_BODY TRUE
J 0
(-2625 3050);
DISPLAY 1.170213 (-2625 3050);
PAINT GREEN (-2625 3050);
DISPLAY INVISIBLE (-2625 3050);
FORCEADD OFFPAGE..1
(-2750 3450);
FORCEPROP 2 LAST $XR0 212 
J 0
(-3002 3450);
DISPLAY 0.638298 (-3002 3450);
PAINT MONO (-3002 3450);
FORCEPROP 2 LAST ROOM PVCCIO_CPU0
J 0
(-3300 3525);
DISPLAY 1.361702 (-3300 3525);
PAINT ORANGE (-3300 3525);
DISPLAY INVISIBLE (-3300 3525);
FORCEPROP 2 LAST CDS_LIB mstr_standard
J 0
(-2750 3450);
PAINT ORANGE (-2750 3450);
DISPLAY INVISIBLE (-2750 3450);
FORCEPROP 2 LAST PATH I39
J 0
(-2700 3525);
DISPLAY 1.021277 (-2700 3525);
PAINT ORANGE (-2700 3525);
DISPLAY INVISIBLE (-2700 3525);
FORCEPROP 1 LAST OFFPAGE TRUE
J 0
(-2425 3325);
DISPLAY 1.170213 (-2425 3325);
PAINT GREEN (-2425 3325);
DISPLAY INVISIBLE (-2425 3325);
FORCEPROP 1 LAST COMMENT_BODY TRUE
J 0
(-2625 3350);
DISPLAY 1.170213 (-2625 3350);
PAINT GREEN (-2625 3350);
DISPLAY INVISIBLE (-2625 3350);
FORCEADD OFFPAGE..1
(-2750 3400);
FORCEPROP 2 LAST $XR0 212 
J 0
(-3002 3400);
DISPLAY 0.638298 (-3002 3400);
PAINT MONO (-3002 3400);
FORCEPROP 2 LAST ROOM PVCCIO_CPU0
J 0
(-3300 3475);
DISPLAY 1.361702 (-3300 3475);
PAINT ORANGE (-3300 3475);
DISPLAY INVISIBLE (-3300 3475);
FORCEPROP 2 LAST CDS_LIB mstr_standard
J 0
(-2750 3400);
PAINT ORANGE (-2750 3400);
DISPLAY INVISIBLE (-2750 3400);
FORCEPROP 2 LAST PATH I40
J 0
(-2700 3475);
DISPLAY 1.021277 (-2700 3475);
PAINT ORANGE (-2700 3475);
DISPLAY INVISIBLE (-2700 3475);
FORCEPROP 1 LAST OFFPAGE TRUE
J 0
(-2425 3275);
DISPLAY 1.170213 (-2425 3275);
PAINT GREEN (-2425 3275);
DISPLAY INVISIBLE (-2425 3275);
FORCEPROP 1 LAST COMMENT_BODY TRUE
J 0
(-2625 3300);
DISPLAY 1.170213 (-2625 3300);
PAINT GREEN (-2625 3300);
DISPLAY INVISIBLE (-2625 3300);
FORCEADD OFFPAGE..1
(-2750 3300);
FORCEPROP 2 LAST $XR0 212 
J 0
(-3002 3300);
DISPLAY 0.638298 (-3002 3300);
PAINT MONO (-3002 3300);
FORCEPROP 2 LAST ROOM PVCCIO_CPU0
J 0
(-3300 3375);
DISPLAY 1.361702 (-3300 3375);
PAINT ORANGE (-3300 3375);
DISPLAY INVISIBLE (-3300 3375);
FORCEPROP 2 LAST CDS_LIB mstr_standard
J 0
(-2750 3300);
PAINT ORANGE (-2750 3300);
DISPLAY INVISIBLE (-2750 3300);
FORCEPROP 2 LAST PATH I42
J 0
(-2700 3375);
DISPLAY 1.021277 (-2700 3375);
PAINT ORANGE (-2700 3375);
DISPLAY INVISIBLE (-2700 3375);
FORCEPROP 1 LAST OFFPAGE TRUE
J 0
(-2425 3175);
DISPLAY 1.170213 (-2425 3175);
PAINT GREEN (-2425 3175);
DISPLAY INVISIBLE (-2425 3175);
FORCEPROP 1 LAST COMMENT_BODY TRUE
J 0
(-2625 3200);
DISPLAY 1.170213 (-2625 3200);
PAINT GREEN (-2625 3200);
DISPLAY INVISIBLE (-2625 3200);
FORCEADD OFFPAGE..1
(-2750 3250);
FORCEPROP 2 LAST $XR0 190 
J 0
(-3002 3250);
DISPLAY 0.638298 (-3002 3250);
PAINT MONO (-3002 3250);
FORCEPROP 2 LAST ROOM PVCCIO_CPU0
J 0
(-3300 3325);
DISPLAY 1.361702 (-3300 3325);
PAINT ORANGE (-3300 3325);
DISPLAY INVISIBLE (-3300 3325);
FORCEPROP 2 LAST CDS_LIB mstr_standard
J 0
(-2750 3250);
PAINT ORANGE (-2750 3250);
DISPLAY INVISIBLE (-2750 3250);
FORCEPROP 2 LAST PATH I43
J 0
(-2700 3325);
DISPLAY 1.021277 (-2700 3325);
PAINT ORANGE (-2700 3325);
DISPLAY INVISIBLE (-2700 3325);
FORCEPROP 1 LAST OFFPAGE TRUE
J 0
(-2425 3125);
DISPLAY 1.170213 (-2425 3125);
PAINT GREEN (-2425 3125);
DISPLAY INVISIBLE (-2425 3125);
FORCEPROP 1 LAST COMMENT_BODY TRUE
J 0
(-2625 3150);
DISPLAY 1.170213 (-2625 3150);
PAINT GREEN (-2625 3150);
DISPLAY INVISIBLE (-2625 3150);
FORCEADD OFFPAGE..2
R 2
(-2750 2400);
FORCEPROP 1 LAST COMMENT_BODY TRUE
J 2
(-2705 2305);
DISPLAY 1.170213 (-2705 2305);
PAINT GREEN (-2705 2305);
DISPLAY INVISIBLE (-2705 2305);
FORCEPROP 1 LAST OFFPAGE TRUE
J 2
(-3075 2275);
DISPLAY 1.170213 (-3075 2275);
PAINT GREEN (-3075 2275);
DISPLAY INVISIBLE (-3075 2275);
FORCEPROP 2 LAST PATH I48
J 0
(-2700 2475);
DISPLAY 1.021277 (-2700 2475);
PAINT ORANGE (-2700 2475);
DISPLAY INVISIBLE (-2700 2475);
FORCEPROP 2 LAST CDS_LIB mstr_standard
J 0
(-2750 2400);
PAINT ORANGE (-2750 2400);
DISPLAY INVISIBLE (-2750 2400);
FORCEPROP 2 LAST ROOM PVCCIO_CPU0
J 0
(-3300 2475);
DISPLAY 1.361702 (-3300 2475);
PAINT ORANGE (-3300 2475);
DISPLAY INVISIBLE (-3300 2475);
FORCEPROP 2 LAST $XR11 226 
J 0
(-3179 2400);
DISPLAY 0.638298 (-3179 2400);
PAINT MONO (-3179 2400);
DISPLAY INVISIBLE (-3179 2400);
FORCEPROP 2 LAST $XR10 223 
J 0
(-3179 2400);
DISPLAY 0.638298 (-3179 2400);
PAINT MONO (-3179 2400);
DISPLAY INVISIBLE (-3179 2400);
FORCEPROP 2 LAST $XR9 218 
J 0
(-3179 2400);
DISPLAY 0.638298 (-3179 2400);
PAINT MONO (-3179 2400);
DISPLAY INVISIBLE (-3179 2400);
FORCEPROP 2 LAST $XR8 215 
J 0
(-3179 2400);
DISPLAY 0.638298 (-3179 2400);
PAINT MONO (-3179 2400);
DISPLAY INVISIBLE (-3179 2400);
FORCEPROP 2 LAST $XR7 206 
J 0
(-3179 2400);
DISPLAY 0.638298 (-3179 2400);
PAINT MONO (-3179 2400);
DISPLAY INVISIBLE (-3179 2400);
FORCEPROP 2 LAST $XR6 201 
J 0
(-3179 2400);
DISPLAY 0.638298 (-3179 2400);
PAINT MONO (-3179 2400);
DISPLAY INVISIBLE (-3179 2400);
FORCEPROP 2 LAST $XR5 194 
J 0
(-3179 2400);
DISPLAY 0.638298 (-3179 2400);
PAINT MONO (-3179 2400);
DISPLAY INVISIBLE (-3179 2400);
FORCEPROP 2 LAST $XR4 193 
J 0
(-3179 2400);
DISPLAY 0.638298 (-3179 2400);
PAINT MONO (-3179 2400);
DISPLAY INVISIBLE (-3179 2400);
FORCEPROP 2 LAST $XR3 235 
J 0
(-3179 2400);
DISPLAY 0.638298 (-3179 2400);
PAINT MONO (-3179 2400);
DISPLAY INVISIBLE (-3179 2400);
FORCEPROP 2 LAST $XR2 213 
J 0
(-3179 2400);
DISPLAY 0.638298 (-3179 2400);
PAINT MONO (-3179 2400);
DISPLAY INVISIBLE (-3179 2400);
FORCEPROP 2 LAST $XR1 159 
J 0
(-3179 2400);
DISPLAY 0.638298 (-3179 2400);
PAINT MONO (-3179 2400);
DISPLAY INVISIBLE (-3179 2400);
FORCEPROP 2 LAST $XR0 138 
J 0
(-3179 2400);
DISPLAY 0.638298 (-3179 2400);
PAINT MONO (-3179 2400);
DISPLAY INVISIBLE (-3179 2400);
FORCEADD OFFPAGE..3
R 2
(-2750 2450);
FORCEPROP 2 LAST $XR11 235 
J 0
(-3630 2414);
DISPLAY 0.638298 (-3630 2414);
PAINT MONO (-3630 2414);
FORCEPROP 2 LAST $XR10 226 
J 0
(-3510 2414);
DISPLAY 0.638298 (-3510 2414);
PAINT MONO (-3510 2414);
FORCEPROP 2 LAST $XR9 223 
J 0
(-3390 2414);
DISPLAY 0.638298 (-3390 2414);
PAINT MONO (-3390 2414);
FORCEPROP 2 LAST $XR8 218 
J 0
(-3270 2414);
DISPLAY 0.638298 (-3270 2414);
PAINT MONO (-3270 2414);
FORCEPROP 2 LAST $XR7 215 
J 0
(-3150 2414);
DISPLAY 0.638298 (-3150 2414);
PAINT MONO (-3150 2414);
FORCEPROP 2 LAST $XR6 213 
J 0
(-3030 2414);
DISPLAY 0.638298 (-3030 2414);
PAINT MONO (-3030 2414);
FORCEPROP 2 LAST $XR5 206 
J 0
(-3630 2450);
DISPLAY 0.638298 (-3630 2450);
PAINT MONO (-3630 2450);
FORCEPROP 2 LAST $XR4 201 
J 0
(-3510 2450);
DISPLAY 0.638298 (-3510 2450);
PAINT MONO (-3510 2450);
FORCEPROP 2 LAST $XR3 194 
J 0
(-3390 2450);
DISPLAY 0.638298 (-3390 2450);
PAINT MONO (-3390 2450);
FORCEPROP 2 LAST $XR2 193 
J 0
(-3270 2450);
DISPLAY 0.638298 (-3270 2450);
PAINT MONO (-3270 2450);
FORCEPROP 2 LAST $XR1 159 
J 0
(-3150 2450);
DISPLAY 0.638298 (-3150 2450);
PAINT MONO (-3150 2450);
FORCEPROP 2 LAST $XR0 138 
J 0
(-3030 2450);
DISPLAY 0.638298 (-3030 2450);
PAINT MONO (-3030 2450);
FORCEPROP 1 LAST COMMENT_BODY TRUE
J 2
(-2700 2350);
DISPLAY 0.872340 (-2700 2350);
PAINT GREEN (-2700 2350);
DISPLAY INVISIBLE (-2700 2350);
FORCEPROP 1 LAST OFFPAGE TRUE
J 2
(-3075 2325);
DISPLAY 0.872340 (-3075 2325);
PAINT GREEN (-3075 2325);
DISPLAY INVISIBLE (-3075 2325);
FORCEPROP 2 LAST PATH I49
J 0
(-2700 2525);
DISPLAY 1.021277 (-2700 2525);
PAINT ORANGE (-2700 2525);
DISPLAY INVISIBLE (-2700 2525);
FORCEPROP 2 LAST CDS_LIB mstr_standard
J 0
(-2750 2450);
PAINT ORANGE (-2750 2450);
DISPLAY INVISIBLE (-2750 2450);
FORCEPROP 2 LAST ROOM PVCCIO_CPU0
J 0
(-3300 2525);
DISPLAY 1.361702 (-3300 2525);
PAINT ORANGE (-3300 2525);
DISPLAY INVISIBLE (-3300 2525);
FORCEADD GND..1
(-1025 2050);
FORCEPROP 3 LASTPIN (-1025 2100) SIG_NAME GND\g
J 0
(-1015 2110);
DISPLAY 0.659574 (-1015 2110);
PAINT MONO (-1015 2110);
DISPLAY INVISIBLE (-1015 2110);
FORCEPROP 1 LAST HDL_POWER GND
J 0
(-1025 2200);
DISPLAY 1.170213 (-1025 2200);
PAINT GREEN (-1025 2200);
DISPLAY INVISIBLE (-1025 2200);
FORCEPROP 1 LAST BODY_TYPE PLUMBING
J 0
(-1070 2007);
DISPLAY 0.340426 (-1070 2007);
PAINT GREEN (-1070 2007);
DISPLAY INVISIBLE (-1070 2007);
FORCEPROP 1 LAST PATH I51
J 0
(-950 2050);
DISPLAY 0.872340 (-950 2050);
PAINT AQUA (-950 2050);
DISPLAY INVISIBLE (-950 2050);
FORCEPROP 2 LAST CDS_LIB mstr_symbols
J 0
(-1025 2050);
PAINT ORANGE (-1025 2050);
DISPLAY INVISIBLE (-1025 2050);
FORCEPROP 1 LAST VOLTAGE 0
J 0
(-1025 2050);
PAINT SKYBLUE (-1025 2050);
DISPLAY INVISIBLE (-1025 2050);
FORCEPROP 2 LAST ROOM PVCCIO_CPU0
J 0
(-1600 2125);
DISPLAY 1.361702 (-1600 2125);
PAINT ORANGE (-1600 2125);
DISPLAY INVISIBLE (-1600 2125);
FORCEPROP 1 LAST SIZE 1B
J 0
(-950 2000);
DISPLAY 1.170213 (-950 2000);
PAINT AQUA (-950 2000);
DISPLAY INVISIBLE (-950 2000);
FORCEADD RES..2
(-925 1200);
FORCEPROP 1 LAST VALUE 3.16K
J 0
(-880 1275);
DISPLAY 0.617021 (-880 1275);
PAINT SKYBLUE (-880 1275);
FORCEPROP 1 LAST TOLERANCE 1%
J 0
(-880 1225);
DISPLAY 0.617021 (-880 1225);
PAINT SKYBLUE (-880 1225);
FORCEPROP 1 LAST MATERIAL CHIP
J 0
(-885 1125);
DISPLAY 0.617021 (-885 1125);
PAINT SKYBLUE (-885 1125);
FORCEPROP 1 LASTPIN (-925 1100) $PN 2
J 0
(-920 1110);
DISPLAY 0.787234 (-920 1110);
PAINT ORANGE (-920 1110);
FORCEPROP 1 LASTPIN (-925 1300) $PN 1
J 0
(-920 1262);
DISPLAY 0.787234 (-920 1262);
PAINT ORANGE (-920 1262);
FORCEPROP 1 LAST WATTAGE 1/16W
J 0
(-885 1175);
DISPLAY 0.617021 (-885 1175);
PAINT SKYBLUE (-885 1175);
FORCEPROP 1 LAST LOCATION R3N31
J 0
(-880 1325);
DISPLAY 0.617021 (-880 1325);
PAINT AQUA (-880 1325);
FORCEPROP 1 LAST PART_NUMBER G21796-043
J 0
(-885 1075);
DISPLAY 0.617021 (-885 1075);
PAINT BLUE (-885 1075);
FORCEPROP 1 LAST PACK_TYPE 0402
J 0
(-885 1025);
DISPLAY 0.617021 (-885 1025);
PAINT SKYBLUE (-885 1025);
FORCEPROP 0 LAST ROOM PVCCIO_CPU0
J 0
(-875 1425);
DISPLAY 1.021277 (-875 1425);
PAINT ORANGE (-875 1425);
DISPLAY INVISIBLE (-875 1425);
FORCEPROP 1 LAST PATH I52
J 0
(-875 1375);
DISPLAY 0.978723 (-875 1375);
PAINT WHITE (-875 1375);
DISPLAY INVISIBLE (-875 1375);
FORCEPROP 2 LAST CDS_LIB mstr_discrete
J 0
(-925 1200);
PAINT ORANGE (-925 1200);
DISPLAY INVISIBLE (-925 1200);
FORCEPROP 2 LAST SEC_TYPE 0402
J 0
(-875 1425);
DISPLAY 1.021277 (-875 1425);
PAINT ORANGE (-875 1425);
DISPLAY INVISIBLE (-875 1425);
FORCEPROP 2 LAST SEC 1
J 0
(-875 1425);
PAINT MONO (-875 1425);
DISPLAY INVISIBLE (-875 1425);
FORCEADD GND..1
(-925 750);
FORCEPROP 3 LASTPIN (-925 800) SIG_NAME GND\g
J 0
(-915 810);
DISPLAY 0.659574 (-915 810);
PAINT MONO (-915 810);
DISPLAY INVISIBLE (-915 810);
FORCEPROP 2 LAST ROOM PVCCIO_CPU0
J 0
(-1500 825);
DISPLAY 1.361702 (-1500 825);
PAINT ORANGE (-1500 825);
DISPLAY INVISIBLE (-1500 825);
FORCEPROP 1 LAST VOLTAGE 0
J 0
(-925 750);
PAINT SKYBLUE (-925 750);
DISPLAY INVISIBLE (-925 750);
FORCEPROP 1 LAST SIZE 1B
J 0
(-850 700);
DISPLAY 1.170213 (-850 700);
PAINT AQUA (-850 700);
DISPLAY INVISIBLE (-850 700);
FORCEPROP 2 LAST CDS_LIB mstr_symbols
J 0
(-925 750);
PAINT ORANGE (-925 750);
DISPLAY INVISIBLE (-925 750);
FORCEPROP 1 LAST PATH I54
J 0
(-850 750);
DISPLAY 0.872340 (-850 750);
PAINT AQUA (-850 750);
DISPLAY INVISIBLE (-850 750);
FORCEPROP 1 LAST BODY_TYPE PLUMBING
J 0
(-970 707);
DISPLAY 0.340426 (-970 707);
PAINT GREEN (-970 707);
DISPLAY INVISIBLE (-970 707);
FORCEPROP 1 LAST HDL_POWER GND
J 0
(-925 900);
DISPLAY 1.170213 (-925 900);
PAINT GREEN (-925 900);
DISPLAY INVISIBLE (-925 900);
FORCEADD RES..2
(775 4100);
FORCEPROP 1 LAST VALUE 1.00K
J 0
(820 4175);
DISPLAY 0.617021 (820 4175);
PAINT SKYBLUE (820 4175);
FORCEPROP 1 LASTPIN (775 4200) $PN 1
J 0
(780 4162);
DISPLAY 0.617021 (780 4162);
PAINT ORANGE (780 4162);
FORCEPROP 1 LAST TOLERANCE 1%
J 0
(820 4125);
DISPLAY 0.617021 (820 4125);
PAINT SKYBLUE (820 4125);
FORCEPROP 1 LAST LOCATION R3P25
J 0
(820 4225);
DISPLAY 0.617021 (820 4225);
PAINT AQUA (820 4225);
FORCEPROP 1 LAST WATTAGE 1/16W
J 0
(815 4075);
DISPLAY 0.617021 (815 4075);
PAINT SKYBLUE (815 4075);
FORCEPROP 1 LAST PART_NUMBER G21796-026
J 0
(815 3975);
DISPLAY 0.617021 (815 3975);
PAINT BLUE (815 3975);
FORCEPROP 1 LASTPIN (775 4000) $PN 2
J 0
(780 4010);
DISPLAY 0.617021 (780 4010);
PAINT ORANGE (780 4010);
FORCEPROP 1 LAST MATERIAL CHIP
J 0
(815 4025);
DISPLAY 0.617021 (815 4025);
PAINT SKYBLUE (815 4025);
FORCEPROP 1 LAST PACK_TYPE 0402
J 0
(815 3925);
DISPLAY 0.617021 (815 3925);
PAINT SKYBLUE (815 3925);
FORCEPROP 2 LAST SEC_TYPE 0402
J 0
(825 4325);
DISPLAY 1.021277 (825 4325);
PAINT ORANGE (825 4325);
DISPLAY INVISIBLE (825 4325);
FORCEPROP 0 LAST SEC 1
J 0
(825 4275);
DISPLAY 0.680851 (825 4275);
PAINT MONO (825 4275);
DISPLAY INVISIBLE (825 4275);
FORCEPROP 2 LAST ROOM PVCCIO_CPU0
J 0
(825 4275);
DISPLAY 1.361702 (825 4275);
PAINT ORANGE (825 4275);
DISPLAY INVISIBLE (825 4275);
FORCEPROP 2 LAST CDS_LIB mstr_discrete
J 0
(775 4100);
PAINT ORANGE (775 4100);
DISPLAY INVISIBLE (775 4100);
FORCEPROP 2 LAST CDS_LOCATION R3P25
J 0
(820 4225);
DISPLAY 0.617021 (820 4225);
PAINT AQUA (820 4225);
DISPLAY INVISIBLE (820 4225);
FORCEPROP 1 LAST PATH I56
J 0
(825 4275);
DISPLAY 0.978723 (825 4275);
PAINT WHITE (825 4275);
DISPLAY INVISIBLE (825 4275);
FORCEADD OFFPAGE..2
(2700 3600);
FORCEPROP 2 LAST $XR1 190 
J 0
(3009 3600);
DISPLAY 0.638298 (3009 3600);
PAINT MONO (3009 3600);
FORCEPROP 2 LAST $XR0 118 
J 0
(2889 3600);
DISPLAY 0.638298 (2889 3600);
PAINT MONO (2889 3600);
FORCEPROP 1 LAST COMMENT_BODY TRUE
J 0
(2655 3505);
DISPLAY 1.170213 (2655 3505);
PAINT GREEN (2655 3505);
DISPLAY INVISIBLE (2655 3505);
FORCEPROP 1 LAST OFFPAGE TRUE
J 0
(3025 3475);
DISPLAY 1.170213 (3025 3475);
PAINT GREEN (3025 3475);
DISPLAY INVISIBLE (3025 3475);
FORCEPROP 2 LAST CDS_LIB mstr_standard
J 0
(2700 3600);
PAINT ORANGE (2700 3600);
DISPLAY INVISIBLE (2700 3600);
FORCEPROP 2 LAST PATH I57
J 0
(2875 3675);
DISPLAY 1.021277 (2875 3675);
PAINT ORANGE (2875 3675);
DISPLAY INVISIBLE (2875 3675);
FORCEPROP 2 LAST ROOM PVCCIO_CPU0
J 0
(2275 3675);
DISPLAY 1.361702 (2275 3675);
PAINT ORANGE (2275 3675);
DISPLAY INVISIBLE (2275 3675);
FORCEADD RES..1
(1875 3600);
FORCEPROP 1 LAST TOLERANCE 1.0%
J 0
(1875 3500);
DISPLAY 0.617021 (1875 3500);
PAINT SKYBLUE (1875 3500);
FORCEPROP 1 LASTPIN (1775 3600) $PN 1
J 0
(1787 3612);
DISPLAY 0.617021 (1787 3612);
PAINT ORANGE (1787 3612);
FORCEPROP 1 LAST VALUE 22.1
J 2
(1850 3500);
DISPLAY 0.617021 (1850 3500);
PAINT SKYBLUE (1850 3500);
FORCEPROP 1 LAST PART_NUMBER G21796-250
J 0
(1825 3700);
DISPLAY 0.617021 (1825 3700);
PAINT BLUE (1825 3700);
FORCEPROP 1 LASTPIN (1975 3600) $PN 2
J 0
(1937 3612);
DISPLAY 0.617021 (1937 3612);
PAINT ORANGE (1937 3612);
FORCEPROP 1 LAST LOCATION R3P20
J 0
(1825 3650);
DISPLAY 0.617021 (1825 3650);
PAINT AQUA (1825 3650);
FORCEPROP 1 LAST WATTAGE 1/16W
J 2
(1850 3450);
DISPLAY 0.617021 (1850 3450);
PAINT SKYBLUE (1850 3450);
FORCEPROP 1 LAST MATERIAL CHIP
J 0
(1875 3450);
DISPLAY 0.617021 (1875 3450);
PAINT SKYBLUE (1875 3450);
FORCEPROP 1 LAST PACK_TYPE 0402
J 0
(2125 3450);
DISPLAY 0.617021 (2125 3450);
PAINT SKYBLUE (2125 3450);
FORCEPROP 2 LAST SEC_TYPE 0402
J 0
(1825 3800);
DISPLAY 1.021277 (1825 3800);
PAINT ORANGE (1825 3800);
DISPLAY INVISIBLE (1825 3800);
FORCEPROP 2 LAST ROOM PVCCIO_CPU0
J 0
(1825 3700);
DISPLAY 1.361702 (1825 3700);
PAINT ORANGE (1825 3700);
DISPLAY INVISIBLE (1825 3700);
FORCEPROP 2 LAST CDS_LIB mstr_discrete
J 0
(1875 3600);
PAINT MONO (1875 3600);
DISPLAY INVISIBLE (1875 3600);
FORCEPROP 2 LAST SEC 1
J 0
(1825 3800);
DISPLAY 0.680851 (1825 3800);
PAINT MONO (1825 3800);
DISPLAY INVISIBLE (1825 3800);
FORCEPROP 2 LAST CDS_LOCATION R3P20
J 0
(1825 3650);
DISPLAY 0.617021 (1825 3650);
PAINT AQUA (1825 3650);
DISPLAY INVISIBLE (1825 3650);
FORCEPROP 1 LAST PATH I58
J 0
(1825 3750);
DISPLAY 0.978723 (1825 3750);
PAINT WHITE (1825 3750);
DISPLAY INVISIBLE (1825 3750);
FORCEADD P3V3_STBY..1
(1800 4775);
FORCEPROP 3 LASTPIN (1800 4725) SIG_NAME P3V3_STBY\g
J 0
(1810 4735);
DISPLAY 0.659574 (1810 4735);
PAINT MONO (1810 4735);
DISPLAY INVISIBLE (1810 4735);
FORCEPROP 1 LAST HDL_POWER P3V3_STBY
J 0
(1500 4650);
DISPLAY 0.872340 (1500 4650);
PAINT ORANGE (1500 4650);
DISPLAY INVISIBLE (1500 4650);
FORCEPROP 1 LAST BODY_TYPE PLUMBING
J 0
(1755 4732);
DISPLAY 0.340426 (1755 4732);
PAINT GREEN (1755 4732);
DISPLAY INVISIBLE (1755 4732);
FORCEPROP 1 LAST VOLTAGE 3.3V
J 0
(1755 4732);
DISPLAY 0.340426 (1755 4732);
PAINT SKYBLUE (1755 4732);
DISPLAY INVISIBLE (1755 4732);
FORCEPROP 2 LAST CDS_LIB mstr_symbols
J 0
(1800 4775);
PAINT ORANGE (1800 4775);
DISPLAY INVISIBLE (1800 4775);
FORCEPROP 1 LAST SIZE 1B
J 0
(1845 4797);
DISPLAY 0.340426 (1845 4797);
PAINT GREEN (1845 4797);
DISPLAY INVISIBLE (1845 4797);
FORCEPROP 1 LAST PATH I59
J 0
(1845 4777);
DISPLAY 0.340426 (1845 4777);
PAINT GREEN (1845 4777);
DISPLAY INVISIBLE (1845 4777);
FORCEADD OFFPAGE..1
R 2
(3025 1600);
FORCEPROP 2 LAST $XR0 211 
J 0
(3211 1600);
DISPLAY 0.638298 (3211 1600);
PAINT MONO (3211 1600);
FORCEPROP 1 LAST COMMENT_BODY TRUE
J 2
(2900 1500);
DISPLAY 1.170213 (2900 1500);
PAINT GREEN (2900 1500);
DISPLAY INVISIBLE (2900 1500);
FORCEPROP 1 LAST OFFPAGE TRUE
J 2
(2700 1475);
DISPLAY 1.170213 (2700 1475);
PAINT GREEN (2700 1475);
DISPLAY INVISIBLE (2700 1475);
FORCEPROP 2 LAST PATH I6
J 0
(3350 1650);
DISPLAY 1.021277 (3350 1650);
PAINT ORANGE (3350 1650);
DISPLAY INVISIBLE (3350 1650);
FORCEPROP 2 LAST ROOM PVCCIO_CPU0
J 0
(2600 1675);
DISPLAY 1.361702 (2600 1675);
PAINT ORANGE (2600 1675);
DISPLAY INVISIBLE (2600 1675);
FORCEPROP 2 LAST CDS_LIB mstr_standard
J 2
(3025 1600);
PAINT ORANGE (3025 1600);
DISPLAY INVISIBLE (3025 1600);
FORCEADD RES..2
(1525 4100);
FORCEPROP 1 LAST TOLERANCE 1.0%
J 0
(1570 4125);
DISPLAY 0.617021 (1570 4125);
PAINT SKYBLUE (1570 4125);
FORCEPROP 1 LAST VALUE 2.26K
J 0
(1570 4175);
DISPLAY 0.617021 (1570 4175);
PAINT SKYBLUE (1570 4175);
FORCEPROP 1 LAST LOCATION R3N23
J 0
(1570 4225);
DISPLAY 0.617021 (1570 4225);
PAINT AQUA (1570 4225);
FORCEPROP 1 LASTPIN (1525 4200) $PN 1
J 0
(1530 4162);
DISPLAY 0.617021 (1530 4162);
PAINT ORANGE (1530 4162);
FORCEPROP 1 LAST WATTAGE 1/16W
J 0
(1565 4075);
DISPLAY 0.617021 (1565 4075);
PAINT SKYBLUE (1565 4075);
FORCEPROP 1 LAST PART_NUMBER G21796-311
J 0
(1565 3975);
DISPLAY 0.617021 (1565 3975);
PAINT BLUE (1565 3975);
FORCEPROP 1 LAST PACK_TYPE 0402
J 0
(1565 3925);
DISPLAY 0.617021 (1565 3925);
PAINT SKYBLUE (1565 3925);
FORCEPROP 1 LAST MATERIAL EMPTY
J 0
(1565 4025);
DISPLAY 0.617021 (1565 4025);
PAINT RED (1565 4025);
FORCEPROP 1 LASTPIN (1525 4000) $PN 2
J 0
(1530 4010);
DISPLAY 0.617021 (1530 4010);
PAINT ORANGE (1530 4010);
FORCEPROP 2 LAST SEC 1
J 0
(1575 4350);
DISPLAY 0.680851 (1575 4350);
PAINT MONO (1575 4350);
DISPLAY INVISIBLE (1575 4350);
FORCEPROP 2 LAST CDS_LOCATION R3N23
J 0
(1570 4225);
DISPLAY 0.617021 (1570 4225);
PAINT AQUA (1570 4225);
DISPLAY INVISIBLE (1570 4225);
FORCEPROP 1 LAST PATH I60
J 0
(1575 4275);
DISPLAY 0.978723 (1575 4275);
PAINT WHITE (1575 4275);
DISPLAY INVISIBLE (1575 4275);
FORCEPROP 2 LAST SEC_TYPE 0402
J 0
(1575 4350);
DISPLAY 1.021277 (1575 4350);
PAINT ORANGE (1575 4350);
DISPLAY INVISIBLE (1575 4350);
FORCEPROP 2 LAST CDS_LIB mstr_discrete
J 0
(1525 4100);
PAINT ORANGE (1525 4100);
DISPLAY INVISIBLE (1525 4100);
FORCEPROP 2 LAST ROOM PVCCIO_CPU0
J 0
(1575 4075);
DISPLAY 1.361702 (1575 4075);
PAINT ORANGE (1575 4075);
DISPLAY INVISIBLE (1575 4075);
FORCEADD RES..1
(1375 3150);
FORCEPROP 1 LAST LOCATION R3P1
J 0
(1325 3200);
DISPLAY 0.617021 (1325 3200);
PAINT AQUA (1325 3200);
FORCEPROP 1 LASTPIN (1275 3150) $PN 1
J 0
(1287 3162);
DISPLAY 0.617021 (1287 3162);
PAINT ORANGE (1287 3162);
FORCEPROP 1 LAST WATTAGE 1/16W
J 2
(1275 3100);
DISPLAY 0.617021 (1275 3100);
PAINT SKYBLUE (1275 3100);
FORCEPROP 1 LAST VALUE 0.0
J 2
(1350 3100);
DISPLAY 0.617021 (1350 3100);
PAINT SKYBLUE (1350 3100);
FORCEPROP 1 LASTPIN (1475 3150) $PN 2
J 0
(1437 3162);
DISPLAY 0.617021 (1437 3162);
PAINT ORANGE (1437 3162);
FORCEPROP 1 LAST PART_NUMBER G21497-005
J 0
(1200 3050);
DISPLAY 0.617021 (1200 3050);
PAINT BLUE (1200 3050);
FORCEPROP 1 LAST MATERIAL CHIP
J 0
(1475 3050);
DISPLAY 0.617021 (1475 3050);
PAINT SKYBLUE (1475 3050);
FORCEPROP 1 LAST PACK_TYPE 0402
J 0
(1475 3100);
DISPLAY 0.617021 (1475 3100);
PAINT SKYBLUE (1475 3100);
FORCEPROP 1 LAST TOLERANCE 5%
J 0
(1375 3100);
DISPLAY 0.617021 (1375 3100);
PAINT SKYBLUE (1375 3100);
FORCEPROP 2 LAST SEC_TYPE 0402
J 0
(1325 3375);
DISPLAY 1.021277 (1325 3375);
PAINT ORANGE (1325 3375);
DISPLAY INVISIBLE (1325 3375);
FORCEPROP 1 LAST PATH I61
J 0
(1325 3300);
DISPLAY 0.978723 (1325 3300);
PAINT WHITE (1325 3300);
DISPLAY INVISIBLE (1325 3300);
FORCEPROP 2 LAST CDS_LOCATION R3P1
J 0
(1325 3200);
DISPLAY 0.617021 (1325 3200);
PAINT AQUA (1325 3200);
DISPLAY INVISIBLE (1325 3200);
FORCEPROP 2 LAST SEC 1
J 0
(1325 3375);
DISPLAY 0.680851 (1325 3375);
PAINT MONO (1325 3375);
DISPLAY INVISIBLE (1325 3375);
FORCEPROP 2 LAST ROOM PVCCIO_CPU0
J 0
(1325 3250);
DISPLAY 1.361702 (1325 3250);
PAINT ORANGE (1325 3250);
DISPLAY INVISIBLE (1325 3250);
FORCEPROP 2 LAST CDS_LIB mstr_discrete
J 0
(1375 3150);
PAINT ORANGE (1375 3150);
DISPLAY INVISIBLE (1375 3150);
FORCEADD OFFPAGE..2
(2700 3150);
FORCEPROP 2 LAST $XR2 21 
J 0
(3129 3150);
DISPLAY 0.638298 (3129 3150);
PAINT MONO (3129 3150);
FORCEPROP 2 LAST $XR1 201 
J 0
(3009 3150);
DISPLAY 0.638298 (3009 3150);
PAINT MONO (3009 3150);
FORCEPROP 2 LAST $XR0 194 
J 0
(2889 3150);
DISPLAY 0.638298 (2889 3150);
PAINT MONO (2889 3150);
FORCEPROP 1 LAST COMMENT_BODY TRUE
J 0
(2655 3055);
DISPLAY 1.170213 (2655 3055);
PAINT GREEN (2655 3055);
DISPLAY INVISIBLE (2655 3055);
FORCEPROP 1 LAST OFFPAGE TRUE
J 0
(3025 3025);
DISPLAY 1.170213 (3025 3025);
PAINT GREEN (3025 3025);
DISPLAY INVISIBLE (3025 3025);
FORCEPROP 2 LAST PATH I62
J 0
(3375 3200);
DISPLAY 1.021277 (3375 3200);
PAINT ORANGE (3375 3200);
DISPLAY INVISIBLE (3375 3200);
FORCEPROP 2 LAST CDS_LIB mstr_standard
J 0
(2700 3150);
PAINT ORANGE (2700 3150);
DISPLAY INVISIBLE (2700 3150);
FORCEPROP 2 LAST ROOM PVCCIO_CPU0
J 0
(2275 3225);
DISPLAY 1.361702 (2275 3225);
PAINT ORANGE (2275 3225);
DISPLAY INVISIBLE (2275 3225);
FORCEADD RES..2
(2075 4050);
FORCEPROP 1 LASTPIN (2075 4150) $PN 1
J 0
(2080 4112);
DISPLAY 0.617021 (2080 4112);
PAINT ORANGE (2080 4112);
FORCEPROP 1 LAST LOCATION R3P18
J 0
(2120 4175);
DISPLAY 0.617021 (2120 4175);
PAINT AQUA (2120 4175);
FORCEPROP 1 LAST TOLERANCE 1%
J 0
(2120 4075);
DISPLAY 0.617021 (2120 4075);
PAINT SKYBLUE (2120 4075);
FORCEPROP 1 LAST MATERIAL CHIP
J 0
(2115 3975);
DISPLAY 0.617021 (2115 3975);
PAINT SKYBLUE (2115 3975);
FORCEPROP 1 LASTPIN (2075 3950) $PN 2
J 0
(2080 3960);
DISPLAY 0.617021 (2080 3960);
PAINT ORANGE (2080 3960);
FORCEPROP 1 LAST VALUE 1.00K
J 0
(2120 4125);
DISPLAY 0.617021 (2120 4125);
PAINT SKYBLUE (2120 4125);
FORCEPROP 1 LAST WATTAGE 1/16W
J 0
(2115 4025);
DISPLAY 0.617021 (2115 4025);
PAINT SKYBLUE (2115 4025);
FORCEPROP 1 LAST PACK_TYPE 0402
J 0
(2115 3875);
DISPLAY 0.617021 (2115 3875);
PAINT SKYBLUE (2115 3875);
FORCEPROP 1 LAST PART_NUMBER G21796-026
J 0
(2115 3925);
DISPLAY 0.617021 (2115 3925);
PAINT BLUE (2115 3925);
FORCEPROP 2 LAST SEC_TYPE 0402
J 0
(2125 4275);
DISPLAY 1.021277 (2125 4275);
PAINT ORANGE (2125 4275);
DISPLAY INVISIBLE (2125 4275);
FORCEPROP 2 LAST SEC 1
J 0
(2125 4275);
DISPLAY 0.680851 (2125 4275);
PAINT MONO (2125 4275);
DISPLAY INVISIBLE (2125 4275);
FORCEPROP 2 LAST CDS_LOCATION R3P18
J 0
(2120 4175);
DISPLAY 0.617021 (2120 4175);
PAINT AQUA (2120 4175);
DISPLAY INVISIBLE (2120 4175);
FORCEPROP 1 LAST PATH I64
J 0
(2125 4225);
DISPLAY 0.978723 (2125 4225);
PAINT WHITE (2125 4225);
DISPLAY INVISIBLE (2125 4225);
FORCEPROP 2 LAST CDS_LIB mstr_discrete
J 0
(2075 4050);
PAINT ORANGE (2075 4050);
DISPLAY INVISIBLE (2075 4050);
FORCEADD CAP..1
(1650 2750);
FORCEPROP 1 LAST VOLTAGE 50V
J 0
(1700 2750);
DISPLAY 0.617021 (1700 2750);
PAINT SKYBLUE (1700 2750);
FORCEPROP 1 LAST PACK_TYPE 0402LF
J 0
(1700 2550);
DISPLAY 0.617021 (1700 2550);
PAINT SKYBLUE (1700 2550);
FORCEPROP 1 LAST LOCATION C3P6
J 0
(1700 2850);
DISPLAY 0.617021 (1700 2850);
PAINT AQUA (1700 2850);
FORCEPROP 1 LASTPIN (1650 2850) $PN 1
J 0
(1660 2830);
DISPLAY 0.617021 (1660 2830);
PAINT ORANGE (1660 2830);
FORCEPROP 1 LAST TOLERANCE 10%
J 0
(1700 2700);
DISPLAY 0.617021 (1700 2700);
PAINT SKYBLUE (1700 2700);
FORCEPROP 1 LAST MATERIAL X7R
J 0
(1700 2650);
DISPLAY 0.617021 (1700 2650);
PAINT SKYBLUE (1700 2650);
FORCEPROP 1 LASTPIN (1650 2650) $PN 2
J 0
(1660 2630);
DISPLAY 0.617021 (1660 2630);
PAINT ORANGE (1660 2630);
FORCEPROP 1 LAST VALUE 1000PF
J 0
(1700 2800);
DISPLAY 0.617021 (1700 2800);
PAINT SKYBLUE (1700 2800);
FORCEPROP 1 LAST PART_NUMBER A36096-046
J 0
(1700 2600);
DISPLAY 0.617021 (1700 2600);
PAINT BLUE (1700 2600);
FORCEPROP 0 LAST ROOM PVCCIO_CPU0_VR
J 0
(1700 2950);
DISPLAY 1.021277 (1700 2950);
PAINT ORANGE (1700 2950);
DISPLAY INVISIBLE (1700 2950);
FORCEPROP 2 LAST SEC 1
J 0
(1700 2950);
DISPLAY 0.680851 (1700 2950);
PAINT MONO (1700 2950);
DISPLAY INVISIBLE (1700 2950);
FORCEPROP 2 LAST SEC_TYPE 0402LF
J 0
(1700 2950);
DISPLAY 1.021277 (1700 2950);
PAINT ORANGE (1700 2950);
DISPLAY INVISIBLE (1700 2950);
FORCEPROP 1 LAST PATH I71
J 0
(1700 2900);
DISPLAY 0.978723 (1700 2900);
PAINT WHITE (1700 2900);
DISPLAY INVISIBLE (1700 2900);
FORCEPROP 2 LAST CDS_LOCATION C3P6
J 0
(1700 2850);
DISPLAY 0.617021 (1700 2850);
PAINT AQUA (1700 2850);
DISPLAY INVISIBLE (1700 2850);
FORCEPROP 2 LAST CDS_LIB mstr_discrete
J 0
(1650 2750);
PAINT MONO (1650 2750);
DISPLAY INVISIBLE (1650 2750);
FORCEADD GND..1
(1650 2475);
FORCEPROP 3 LASTPIN (1650 2525) SIG_NAME GND\g
J 0
(1660 2535);
DISPLAY 0.659574 (1660 2535);
PAINT MONO (1660 2535);
DISPLAY INVISIBLE (1660 2535);
FORCEPROP 1 LAST HDL_POWER GND
J 0
(1650 2625);
DISPLAY 1.170213 (1650 2625);
PAINT GREEN (1650 2625);
DISPLAY INVISIBLE (1650 2625);
FORCEPROP 1 LAST BODY_TYPE PLUMBING
J 0
(1605 2432);
DISPLAY 0.340426 (1605 2432);
PAINT GREEN (1605 2432);
DISPLAY INVISIBLE (1605 2432);
FORCEPROP 1 LAST VOLTAGE 0
J 0
(1650 2475);
PAINT SKYBLUE (1650 2475);
DISPLAY INVISIBLE (1650 2475);
FORCEPROP 2 LAST CDS_LIB mstr_symbols
J 0
(1650 2475);
PAINT MONO (1650 2475);
DISPLAY INVISIBLE (1650 2475);
FORCEPROP 1 LAST SIZE 1B
J 0
(1725 2425);
DISPLAY 1.170213 (1725 2425);
PAINT AQUA (1725 2425);
DISPLAY INVISIBLE (1725 2425);
FORCEPROP 1 LAST PATH I72
J 0
(1725 2475);
DISPLAY 0.872340 (1725 2475);
PAINT AQUA (1725 2475);
DISPLAY INVISIBLE (1725 2475);
FORCEPROP 2 LAST ROOM PVCCIO_CPU0
J 0
(1075 2550);
DISPLAY 1.361702 (1075 2550);
PAINT ORANGE (1075 2550);
DISPLAY INVISIBLE (1075 2550);
FORCEADD RES..1
(-2600 2050);
FORCEPROP 1 LASTPIN (-2500 2050) $PN 2
J 0
(-2538 2062);
DISPLAY 0.617021 (-2538 2062);
PAINT ORANGE (-2538 2062);
FORCEPROP 1 LAST PACK_TYPE 0402
J 0
(-2575 1950);
DISPLAY 0.617021 (-2575 1950);
PAINT SKYBLUE (-2575 1950);
FORCEPROP 1 LAST PART_NUMBER G21796-066
J 0
(-2750 2000);
DISPLAY 0.617021 (-2750 2000);
PAINT BLUE (-2750 2000);
FORCEPROP 1 LAST MATERIAL CHIP
J 0
(-2575 1900);
DISPLAY 0.617021 (-2575 1900);
PAINT SKYBLUE (-2575 1900);
FORCEPROP 1 LAST VALUE 10.0
J 2
(-2700 1950);
DISPLAY 0.617021 (-2700 1950);
PAINT SKYBLUE (-2700 1950);
FORCEPROP 1 LAST LOCATION R3N19
J 0
(-2650 2100);
DISPLAY 0.617021 (-2650 2100);
PAINT AQUA (-2650 2100);
FORCEPROP 1 LAST TOLERANCE 1%
J 0
(-2675 1950);
DISPLAY 0.617021 (-2675 1950);
PAINT SKYBLUE (-2675 1950);
FORCEPROP 1 LAST WATTAGE 1/16W
J 2
(-2600 1900);
DISPLAY 0.617021 (-2600 1900);
PAINT SKYBLUE (-2600 1900);
FORCEPROP 1 LASTPIN (-2700 2050) $PN 1
J 0
(-2688 2062);
DISPLAY 0.617021 (-2688 2062);
PAINT ORANGE (-2688 2062);
FORCEPROP 2 LAST SEC_TYPE 0402
J 0
(-2650 2250);
DISPLAY 1.021277 (-2650 2250);
PAINT ORANGE (-2650 2250);
DISPLAY INVISIBLE (-2650 2250);
FORCEPROP 2 LAST SEC 1
J 0
(-2650 2250);
DISPLAY 0.680851 (-2650 2250);
PAINT MONO (-2650 2250);
DISPLAY INVISIBLE (-2650 2250);
FORCEPROP 2 LAST ROOM PVCCIO_CPU0
J 0
(-2525 2150);
DISPLAY 1.361702 (-2525 2150);
PAINT ORANGE (-2525 2150);
DISPLAY INVISIBLE (-2525 2150);
FORCEPROP 2 LAST CDS_LIB mstr_discrete
J 0
(-2600 2050);
PAINT ORANGE (-2600 2050);
DISPLAY INVISIBLE (-2600 2050);
FORCEPROP 2 LAST CDS_LOCATION R3N19
J 0
(-2650 2100);
DISPLAY 0.617021 (-2650 2100);
PAINT AQUA (-2650 2100);
DISPLAY INVISIBLE (-2650 2100);
FORCEPROP 1 LAST PATH I81
J 0
(-2650 2200);
DISPLAY 0.978723 (-2650 2200);
PAINT WHITE (-2650 2200);
DISPLAY INVISIBLE (-2650 2200);
FORCEADD OFFPAGE..1
(-3425 2050);
FORCEPROP 2 LAST $XR0 212 
J 0
(-3707 2050);
DISPLAY 0.638298 (-3707 2050);
PAINT MONO (-3707 2050);
FORCEPROP 1 LAST COMMENT_BODY TRUE
J 0
(-3300 1950);
DISPLAY 1.170213 (-3300 1950);
PAINT GREEN (-3300 1950);
DISPLAY INVISIBLE (-3300 1950);
FORCEPROP 1 LAST OFFPAGE TRUE
J 0
(-3100 1925);
DISPLAY 1.170213 (-3100 1925);
PAINT GREEN (-3100 1925);
DISPLAY INVISIBLE (-3100 1925);
FORCEPROP 2 LAST CDS_LIB mstr_standard
J 0
(-3425 2050);
PAINT ORANGE (-3425 2050);
DISPLAY INVISIBLE (-3425 2050);
FORCEPROP 2 LAST PATH I82
J 0
(-3700 2100);
DISPLAY 1.021277 (-3700 2100);
PAINT ORANGE (-3700 2100);
DISPLAY INVISIBLE (-3700 2100);
FORCEPROP 2 LAST ROOM PVCCIO_CPU0
J 0
(-3975 2125);
DISPLAY 1.361702 (-3975 2125);
PAINT ORANGE (-3975 2125);
DISPLAY INVISIBLE (-3975 2125);
FORCEADD CAP..1
(-2400 1850);
FORCEPROP 1 LAST VALUE 220PF
J 0
(-2350 1900);
DISPLAY 0.617021 (-2350 1900);
PAINT SKYBLUE (-2350 1900);
FORCEPROP 1 LAST MATERIAL X7R
J 0
(-2275 1850);
DISPLAY 0.617021 (-2275 1850);
PAINT SKYBLUE (-2275 1850);
FORCEPROP 1 LAST TOLERANCE 10%
J 0
(-2200 1900);
DISPLAY 0.617021 (-2200 1900);
PAINT SKYBLUE (-2200 1900);
FORCEPROP 1 LAST PART_NUMBER A36096-050
J 0
(-2350 1800);
DISPLAY 0.617021 (-2350 1800);
PAINT BLUE (-2350 1800);
FORCEPROP 1 LAST PACK_TYPE 0402LF
J 0
(-2350 1750);
DISPLAY 0.617021 (-2350 1750);
PAINT SKYBLUE (-2350 1750);
FORCEPROP 1 LAST VOLTAGE 50V
J 0
(-2350 1850);
DISPLAY 0.617021 (-2350 1850);
PAINT SKYBLUE (-2350 1850);
FORCEPROP 1 LAST LOCATION C3N39
J 0
(-2350 1950);
DISPLAY 0.617021 (-2350 1950);
PAINT AQUA (-2350 1950);
FORCEPROP 1 LASTPIN (-2400 1950) $PN 1
J 0
(-2390 1930);
DISPLAY 0.617021 (-2390 1930);
PAINT ORANGE (-2390 1930);
FORCEPROP 1 LASTPIN (-2400 1750) $PN 2
J 0
(-2390 1730);
DISPLAY 0.617021 (-2390 1730);
PAINT ORANGE (-2390 1730);
FORCEPROP 2 LAST SEC 1
J 0
(-2350 2075);
DISPLAY 0.680851 (-2350 2075);
PAINT MONO (-2350 2075);
DISPLAY INVISIBLE (-2350 2075);
FORCEPROP 2 LAST SEC_TYPE 0402LF
J 0
(-2350 2075);
DISPLAY 1.021277 (-2350 2075);
PAINT ORANGE (-2350 2075);
DISPLAY INVISIBLE (-2350 2075);
FORCEPROP 2 LAST ROOM PVCCIO_CPU0
J 0
(-2350 2000);
DISPLAY 1.361702 (-2350 2000);
PAINT ORANGE (-2350 2000);
DISPLAY INVISIBLE (-2350 2000);
FORCEPROP 1 LAST PATH I83
J 0
(-2350 2000);
DISPLAY 0.978723 (-2350 2000);
PAINT WHITE (-2350 2000);
DISPLAY INVISIBLE (-2350 2000);
FORCEPROP 2 LAST CDS_LOCATION C3N39
J 0
(-2350 1950);
DISPLAY 0.617021 (-2350 1950);
PAINT AQUA (-2350 1950);
DISPLAY INVISIBLE (-2350 1950);
FORCEPROP 2 LAST CDS_LIB mstr_discrete
J 0
(-2400 1850);
PAINT ORANGE (-2400 1850);
DISPLAY INVISIBLE (-2400 1850);
FORCEADD OFFPAGE..1
(-3350 1650);
FORCEPROP 2 LAST $XR0 212 
J 0
(-3602 1650);
DISPLAY 0.638298 (-3602 1650);
PAINT MONO (-3602 1650);
FORCEPROP 1 LAST COMMENT_BODY TRUE
J 0
(-3225 1550);
DISPLAY 1.170213 (-3225 1550);
PAINT GREEN (-3225 1550);
DISPLAY INVISIBLE (-3225 1550);
FORCEPROP 1 LAST OFFPAGE TRUE
J 0
(-3025 1525);
DISPLAY 1.170213 (-3025 1525);
PAINT GREEN (-3025 1525);
DISPLAY INVISIBLE (-3025 1525);
FORCEPROP 2 LAST CDS_LIB mstr_standard
J 0
(-3350 1650);
PAINT ORANGE (-3350 1650);
DISPLAY INVISIBLE (-3350 1650);
FORCEPROP 2 LAST ROOM PVCCIO_CPU0
J 0
(-3900 1725);
DISPLAY 1.361702 (-3900 1725);
PAINT ORANGE (-3900 1725);
DISPLAY INVISIBLE (-3900 1725);
FORCEPROP 2 LAST PATH I84
J 0
(-3625 1700);
DISPLAY 1.021277 (-3625 1700);
PAINT ORANGE (-3625 1700);
DISPLAY INVISIBLE (-3625 1700);
FORCEADD RES..1
(-1950 3250);
FORCEPROP 1 LAST PART_NUMBER G21497-005
J 0
(-2100 3200);
DISPLAY 0.617021 (-2100 3200);
PAINT BLUE (-2100 3200);
FORCEPROP 1 LAST WATTAGE 1/16W
J 2
(-1975 3100);
DISPLAY 0.617021 (-1975 3100);
PAINT SKYBLUE (-1975 3100);
FORCEPROP 1 LASTPIN (-1850 3250) $PN 2
J 0
(-1888 3262);
DISPLAY 0.787234 (-1888 3262);
PAINT ORANGE (-1888 3262);
FORCEPROP 1 LAST LOCATION R3P26
J 0
(-2000 3300);
DISPLAY 0.617021 (-2000 3300);
PAINT AQUA (-2000 3300);
FORCEPROP 1 LASTPIN (-2050 3250) $PN 1
J 0
(-2038 3262);
DISPLAY 0.787234 (-2038 3262);
PAINT ORANGE (-2038 3262);
FORCEPROP 1 LAST PACK_TYPE 0402
J 0
(-1875 3150);
DISPLAY 0.617021 (-1875 3150);
PAINT SKYBLUE (-1875 3150);
FORCEPROP 1 LAST TOLERANCE 5%
J 0
(-2000 3150);
DISPLAY 0.617021 (-2000 3150);
PAINT SKYBLUE (-2000 3150);
FORCEPROP 1 LAST VALUE 0.0
J 2
(-2050 3150);
DISPLAY 0.617021 (-2050 3150);
PAINT SKYBLUE (-2050 3150);
FORCEPROP 1 LAST MATERIAL CHIP
J 0
(-1950 3100);
DISPLAY 0.617021 (-1950 3100);
PAINT SKYBLUE (-1950 3100);
FORCEPROP 2 LAST SEC_TYPE 0402
J 0
(-2000 3450);
DISPLAY 1.021277 (-2000 3450);
PAINT ORANGE (-2000 3450);
DISPLAY INVISIBLE (-2000 3450);
FORCEPROP 2 LAST SEC 1
J 0
(-2000 3450);
PAINT MONO (-2000 3450);
DISPLAY INVISIBLE (-2000 3450);
FORCEPROP 1 LAST PATH I87
J 0
(-2000 3400);
DISPLAY 0.978723 (-2000 3400);
PAINT WHITE (-2000 3400);
DISPLAY INVISIBLE (-2000 3400);
FORCEPROP 2 LAST ROOM PVCCIN_CPU0_VR
J 0
(-2000 3350);
DISPLAY 1.361702 (-2000 3350);
PAINT ORANGE (-2000 3350);
DISPLAY INVISIBLE (-2000 3350);
FORCEPROP 2 LAST CDS_LOCATION R3P26
J 0
(-2000 3300);
DISPLAY 0.617021 (-2000 3300);
PAINT AQUA (-2000 3300);
DISPLAY INVISIBLE (-2000 3300);
FORCEPROP 2 LAST CDS_LIB mstr_discrete
J 0
(-1950 3250);
PAINT ORANGE (-1950 3250);
DISPLAY INVISIBLE (-1950 3250);
FORCEADD RES..2
(-1125 4300);
FORCEPROP 1 LAST TOLERANCE 1%
J 0
(-1080 4325);
DISPLAY 0.617021 (-1080 4325);
PAINT SKYBLUE (-1080 4325);
FORCEPROP 1 LAST PART_NUMBER G21796-010
J 0
(-1085 4175);
DISPLAY 0.617021 (-1085 4175);
PAINT BLUE (-1085 4175);
FORCEPROP 1 LAST PACK_TYPE 0402
J 0
(-1085 4125);
DISPLAY 0.617021 (-1085 4125);
PAINT SKYBLUE (-1085 4125);
FORCEPROP 1 LAST LOCATION R3P21
J 0
(-1080 4425);
DISPLAY 0.617021 (-1080 4425);
PAINT AQUA (-1080 4425);
FORCEPROP 1 LAST MATERIAL EMPTY
J 0
(-1085 4225);
DISPLAY 0.617021 (-1085 4225);
PAINT RED (-1085 4225);
FORCEPROP 1 LAST WATTAGE 1/16W
J 0
(-1085 4275);
DISPLAY 0.617021 (-1085 4275);
PAINT SKYBLUE (-1085 4275);
FORCEPROP 1 LAST VALUE 100.0K
J 0
(-1080 4375);
DISPLAY 0.617021 (-1080 4375);
PAINT SKYBLUE (-1080 4375);
FORCEPROP 0 LAST BOM_COST SM_CONTROLLER
J 0
(-1075 4625);
DISPLAY 1.021277 (-1075 4625);
PAINT ORANGE (-1075 4625);
DISPLAY INVISIBLE (-1075 4625);
FORCEPROP 2 LAST CDS_SEC 1
J 0
(-1075 4525);
PAINT MONO (-1075 4525);
DISPLAY INVISIBLE (-1075 4525);
FORCEPROP 2 LAST $SEC 1
J 0
(-1075 4525);
PAINT MONO (-1075 4525);
DISPLAY INVISIBLE (-1075 4525);
FORCEPROP 2 LAST CDS_LOCATION R3P21
J 0
(-1080 4425);
DISPLAY 0.617021 (-1080 4425);
PAINT AQUA (-1080 4425);
DISPLAY INVISIBLE (-1080 4425);
FORCEPROP 1 LAST PATH I88
J 0
(-1075 4475);
DISPLAY 0.978723 (-1075 4475);
PAINT WHITE (-1075 4475);
DISPLAY INVISIBLE (-1075 4475);
FORCEPROP 0 LAST ROOM BMC
J 0
(-1075 4525);
DISPLAY 0.617021 (-1075 4525);
PAINT ORANGE (-1075 4525);
DISPLAY INVISIBLE (-1075 4525);
FORCEPROP 1 LASTPIN (-1125 4400) $PN 1
J 0
(-1120 4362);
DISPLAY 0.787234 (-1120 4362);
PAINT ORANGE (-1120 4362);
DISPLAY INVISIBLE (-1120 4362);
FORCEPROP 2 LAST CDS_LIB mstr_discrete
J 0
(-1125 4300);
PAINT ORANGE (-1125 4300);
DISPLAY INVISIBLE (-1125 4300);
FORCEPROP 1 LASTPIN (-1125 4200) $PN 2
J 0
(-1120 4210);
DISPLAY 0.787234 (-1120 4210);
PAINT ORANGE (-1120 4210);
DISPLAY INVISIBLE (-1120 4210);
FORCEADD PXE1110B..1
(100 2850);
FORCEPROP 2 LASTPIN (550 3050) $PN 3
J 0
(560 3060);
DISPLAY 0.617021 (560 3060);
PAINT ORANGE (560 3060);
FORCEPROP 2 LASTPIN (550 3150) $PN 17
J 0
(560 3160);
DISPLAY 0.617021 (560 3160);
PAINT ORANGE (560 3160);
FORCEPROP 2 LASTPIN (550 2300) $PN 41
J 0
(560 2310);
DISPLAY 0.617021 (560 2310);
PAINT ORANGE (560 2310);
FORCEPROP 2 LASTPIN (-350 2550) $PN 30
J 2
(-360 2560);
DISPLAY 0.617021 (-360 2560);
PAINT ORANGE (-360 2560);
FORCEPROP 2 LASTPIN (-350 2600) $PN 29
J 2
(-360 2610);
DISPLAY 0.617021 (-360 2610);
PAINT ORANGE (-360 2610);
FORCEPROP 2 LASTPIN (-350 3300) $PN 35
J 2
(-360 3310);
DISPLAY 0.617021 (-360 3310);
PAINT ORANGE (-360 3310);
FORCEPROP 2 LASTPIN (-350 3150) $PN 37
J 2
(-360 3160);
DISPLAY 0.617021 (-360 3160);
PAINT ORANGE (-360 3160);
FORCEPROP 1 LAST LOCATION EU3P1
J 0
(-300 3775);
DISPLAY 0.617021 (-300 3775);
PAINT AQUA (-300 3775);
FORCEPROP 1 LAST MATERIAL IC
J 0
(-300 3725);
DISPLAY 0.617021 (-300 3725);
PAINT SKYBLUE (-300 3725);
FORCEPROP 2 LASTPIN (-350 3450) $PN 21
J 2
(-360 3460);
DISPLAY 0.617021 (-360 3460);
PAINT ORANGE (-360 3460);
FORCEPROP 2 LASTPIN (-350 3400) $PN 22
J 2
(-360 3410);
DISPLAY 0.617021 (-360 3410);
PAINT ORANGE (-360 3410);
FORCEPROP 2 LASTPIN (-350 3250) $PN 10
J 2
(-360 3260);
DISPLAY 0.617021 (-360 3260);
PAINT ORANGE (-360 3260);
FORCEPROP 2 LASTPIN (-350 3000) $PN 40
J 2
(-360 3010);
DISPLAY 0.617021 (-360 3010);
PAINT ORANGE (-360 3010);
FORCEPROP 2 LASTPIN (550 3250) $PN 11
J 0
(560 3260);
DISPLAY 0.617021 (560 3260);
PAINT ORANGE (560 3260);
FORCEPROP 2 LASTPIN (-350 3100) $PN 38
J 2
(-360 3110);
DISPLAY 0.617021 (-360 3110);
PAINT ORANGE (-360 3110);
FORCEPROP 2 LASTPIN (-350 2650) $PN 20
J 2
(-360 2660);
DISPLAY 0.617021 (-360 2660);
PAINT ORANGE (-360 2660);
FORCEPROP 2 LASTPIN (550 2500) $PN 4
J 0
(560 2510);
DISPLAY 0.617021 (560 2510);
PAINT ORANGE (560 2510);
FORCEPROP 2 LASTPIN (-350 3600) $PN 39
J 2
(-360 3610);
DISPLAY 0.617021 (-360 3610);
PAINT ORANGE (-360 3610);
FORCEPROP 2 LASTPIN (-350 3550) $PN 15
J 2
(-360 3560);
DISPLAY 0.617021 (-360 3560);
PAINT ORANGE (-360 3560);
FORCEPROP 2 LASTPIN (-350 2450) $PN 6
J 2
(-360 2460);
DISPLAY 0.617021 (-360 2460);
PAINT ORANGE (-360 2460);
FORCEPROP 2 LASTPIN (-350 2400) $PN 7
J 2
(-360 2410);
DISPLAY 0.617021 (-360 2410);
PAINT ORANGE (-360 2410);
FORCEPROP 2 LASTPIN (550 2600) $PN 28
J 0
(560 2610);
DISPLAY 0.617021 (560 2610);
PAINT ORANGE (560 2610);
FORCEPROP 2 LASTPIN (550 3000) $PN 5
J 0
(560 3010);
DISPLAY 0.617021 (560 3010);
PAINT ORANGE (560 3010);
FORCEPROP 2 LASTPIN (550 3600) $PN 9
J 0
(560 3610);
DISPLAY 0.617021 (560 3610);
PAINT ORANGE (560 3610);
FORCEPROP 2 LASTPIN (550 3450) $PN 12
J 0
(560 3460);
DISPLAY 0.617021 (560 3460);
PAINT ORANGE (560 3460);
FORCEPROP 2 LASTPIN (-350 2950) $PN 16
J 2
(-360 2960);
DISPLAY 0.617021 (-360 2960);
PAINT ORANGE (-360 2960);
FORCEPROP 2 LASTPIN (550 2800) $PN 18
J 0
(560 2810);
DISPLAY 0.617021 (560 2810);
PAINT ORANGE (560 2810);
FORCEPROP 2 LASTPIN (550 2700) $PN 13
J 0
(560 2710);
DISPLAY 0.617021 (560 2710);
PAINT ORANGE (560 2710);
FORCEPROP 2 LASTPIN (550 2100) $PN 27
J 0
(560 2110);
DISPLAY 0.617021 (560 2110);
PAINT ORANGE (560 2110);
FORCEPROP 2 LASTPIN (550 2550) $PN 24
J 0
(560 2560);
DISPLAY 0.617021 (560 2560);
PAINT ORANGE (560 2560);
FORCEPROP 2 LASTPIN (550 2750) $PN 14
J 0
(560 2760);
DISPLAY 0.617021 (560 2760);
PAINT ORANGE (560 2760);
FORCEPROP 2 LASTPIN (-350 2300) $PN 34
J 2
(-360 2310);
DISPLAY 0.617021 (-360 2310);
PAINT ORANGE (-360 2310);
FORCEPROP 2 LASTPIN (-350 2050) $PN 33
J 2
(-360 2060);
DISPLAY 0.617021 (-360 2060);
PAINT ORANGE (-360 2060);
FORCEPROP 2 LASTPIN (-350 2100) $PN 36
J 2
(-360 2110);
DISPLAY 0.617021 (-360 2110);
PAINT ORANGE (-360 2110);
FORCEPROP 2 LASTPIN (-350 2200) $PN 25
J 2
(-360 2210);
DISPLAY 0.617021 (-360 2210);
PAINT ORANGE (-360 2210);
FORCEPROP 2 LASTPIN (-350 2150) $PN 26
J 2
(-360 2160);
DISPLAY 0.617021 (-360 2160);
PAINT ORANGE (-360 2160);
FORCEPROP 2 LASTPIN (550 2150) $PN 23
J 0
(560 2160);
DISPLAY 0.617021 (560 2160);
PAINT ORANGE (560 2160);
FORCEPROP 2 LASTPIN (-350 2700) $PN 19
J 2
(-360 2710);
DISPLAY 0.617021 (-360 2710);
PAINT ORANGE (-360 2710);
FORCEPROP 2 LASTPIN (-350 2800) $PN 8
J 2
(-360 2810);
DISPLAY 0.617021 (-360 2810);
PAINT ORANGE (-360 2810);
FORCEPROP 2 LASTPIN (550 2400) $PN 1
J 0
(560 2410);
DISPLAY 0.617021 (560 2410);
PAINT ORANGE (560 2410);
FORCEPROP 2 LASTPIN (550 2450) $PN 2
J 0
(560 2460);
DISPLAY 0.617021 (560 2460);
PAINT ORANGE (560 2460);
FORCEPROP 2 LASTPIN (550 2850) $PN 31
J 0
(560 2860);
DISPLAY 0.617021 (560 2860);
PAINT ORANGE (560 2860);
FORCEPROP 2 LASTPIN (550 2900) $PN 32
J 0
(560 2910);
DISPLAY 0.617021 (560 2910);
PAINT ORANGE (560 2910);
FORCEPROP 1 LAST PART_NUMBER H89187-001
J 0
(-300 1950);
DISPLAY 0.617021 (-300 1950);
PAINT BLUE (-300 1950);
FORCEPROP 1 LAST PATH I93
J 0
(200 3726);
PAINT WHITE (200 3726);
DISPLAY INVISIBLE (200 3726);
FORCEPROP 1 LAST CDS_LMAN_SYM_OUTLINE -400,850,400,-850
J 0
(100 2850);
DISPLAY 0.468085 (100 2850);
PAINT GREEN (100 2850);
DISPLAY INVISIBLE (100 2850);
FORCEPROP 2 LAST CDS_LIB mstr_controller
J 0
(100 2850);
PAINT ORANGE (100 2850);
DISPLAY INVISIBLE (100 2850);
FORCEPROP 1 LAST PACK_TYPE QFN
J 0
(-300 3825);
PAINT SKYBLUE (-300 3825);
DISPLAY INVISIBLE (-300 3825);
FORCEPROP 2 LAST SEC_TYPE QFN
J 0
(-300 3825);
DISPLAY 1.021277 (-300 3825);
PAINT ORANGE (-300 3825);
DISPLAY INVISIBLE (-300 3825);
FORCEPROP 2 LAST SEC 1
J 0
(-300 3825);
DISPLAY 0.680851 (-300 3825);
PAINT MONO (-300 3825);
DISPLAY INVISIBLE (-300 3825);
FORCEPROP 2 LAST CDS_LOCATION EU3P1
J 0
(-300 3775);
PAINT WHITE (-300 3775);
DISPLAY INVISIBLE (-300 3775);
FORCEADD SC22P50V2JN-4GP..1
R 1
(-1975 3600);
FORCEPROP 0 LAST GROUP POWER_FAIR
J 0
(-2100 3525);
DISPLAY 0.638298 (-2100 3525);
PAINT BROWN (-2100 3525);
DISPLAY BOTH (-2100 3525);
FORCEPROP 2 LAST TOLERANCE 5%
J 0
(-1450 3650);
DISPLAY 0.638298 (-1450 3650);
PAINT GREEN (-1450 3650);
FORCEPROP 2 LAST ATTRIBUTE 22PF
J 0
(-1575 3650);
DISPLAY 0.638298 (-1575 3650);
PAINT GREEN (-1575 3650);
FORCEPROP 2 LAST TYPE NPO
J 0
(-1575 3600);
DISPLAY 0.638298 (-1575 3600);
PAINT GREEN (-1575 3600);
FORCEPROP 1 LAST VALUE SC22P50V2JN-4GP
J 0
(-2000 3650);
DISPLAY 0.617021 (-2000 3650);
PAINT GREEN (-2000 3650);
FORCEPROP 1 LAST LOCATION CF13
J 0
(-2130 3650);
DISPLAY 0.617021 (-2130 3650);
PAINT GREEN (-2130 3650);
FORCEPROP 2 LAST RATED 50V
J 0
(-1350 3650);
DISPLAY 0.638298 (-1350 3650);
PAINT GREEN (-1350 3650);
FORCEPROP 2 LAST PACK_SIZE 0402
J 0
(-1450 3600);
DISPLAY 0.638298 (-1450 3600);
PAINT GREEN (-1450 3600);
FORCEPROP 2 LAST CDS_LIB w_hdl
J 0
(-1975 3600);
PAINT MONO (-1975 3600);
DISPLAY INVISIBLE (-1975 3600);
FORCEPROP 1 LAST CDS_LMAN_SYM_OUTLINE -50,25,50,-25
R 1
J 0
(-1975 3600);
DISPLAY 0.468085 (-1975 3600);
PAINT GREEN (-1975 3600);
DISPLAY INVISIBLE (-1975 3600);
FORCEPROP 1 LAST PATH I95
R 1
J 0
(-1975 3600);
DISPLAY 0.617021 (-1975 3600);
PAINT GREEN (-1975 3600);
DISPLAY INVISIBLE (-1975 3600);
FORCEPROP 1 LAST PART_NUMBER 78.22034.1FL
R 1
J 0
(-1975 3600);
DISPLAY 0.617021 (-1975 3600);
PAINT GREEN (-1975 3600);
DISPLAY INVISIBLE (-1975 3600);
FORCEPROP 1 LAST PACK_TYPE SMD-BCG
R 1
J 0
(-1975 3600);
DISPLAY 0.617021 (-1975 3600);
PAINT GREEN (-1975 3600);
DISPLAY INVISIBLE (-1975 3600);
FORCEADD RES..1
(-1975 3750);
FORCEPROP 1 LASTPIN (-1875 3750) $PN 2
J 0
(-1913 3762);
DISPLAY 0.787234 (-1913 3762);
PAINT ORANGE (-1913 3762);
FORCEPROP 1 LASTPIN (-2075 3750) $PN 1
J 0
(-2063 3762);
DISPLAY 0.787234 (-2063 3762);
PAINT ORANGE (-2063 3762);
FORCEPROP 1 LAST MATERIAL CHIP
J 0
(-1725 3800);
DISPLAY 0.617021 (-1725 3800);
PAINT SKYBLUE (-1725 3800);
FORCEPROP 1 LAST VALUE 1.0K
J 2
(-2050 3800);
DISPLAY 0.617021 (-2050 3800);
PAINT SKYBLUE (-2050 3800);
FORCEPROP 1 LAST TOLERANCE 0.1%
J 0
(-2000 3800);
DISPLAY 0.617021 (-2000 3800);
PAINT SKYBLUE (-2000 3800);
FORCEPROP 1 LAST PART_NUMBER G85996-004
J 0
(-2025 3850);
DISPLAY 0.617021 (-2025 3850);
PAINT BLUE (-2025 3850);
FORCEPROP 1 LAST PACK_TYPE 0402
J 0
(-1875 3800);
DISPLAY 0.617021 (-1875 3800);
PAINT SKYBLUE (-1875 3800);
FORCEPROP 1 LAST WATTAGE 1/16W
J 2
(-1625 3850);
DISPLAY 0.617021 (-1625 3850);
PAINT SKYBLUE (-1625 3850);
FORCEPROP 1 LAST LOCATION RF13
J 0
(-2150 3850);
DISPLAY 0.617021 (-2150 3850);
PAINT AQUA (-2150 3850);
FORCEPROP 0 LAST GROUP POWER_FAIR
J 0
(-2075 3700);
DISPLAY 0.638298 (-2075 3700);
PAINT BROWN (-2075 3700);
DISPLAY BOTH (-2075 3700);
FORCEPROP 2 LAST SEC_TYPE 0402
J 0
(-2025 3950);
DISPLAY 1.021277 (-2025 3950);
PAINT ORANGE (-2025 3950);
DISPLAY INVISIBLE (-2025 3950);
FORCEPROP 0 LAST SEC 1
J 0
(-1900 3900);
DISPLAY 0.680851 (-1900 3900);
PAINT MONO (-1900 3900);
DISPLAY INVISIBLE (-1900 3900);
FORCEPROP 2 LAST CDS_LIB mstr_discrete
J 0
(-1975 3750);
PAINT MONO (-1975 3750);
DISPLAY INVISIBLE (-1975 3750);
FORCEPROP 0 LAST ROOM SB
J 0
(-1925 3975);
DISPLAY 1.021277 (-1925 3975);
PAINT ORANGE (-1925 3975);
DISPLAY INVISIBLE (-1925 3975);
FORCEPROP 1 LAST PATH I96
J 0
(-2025 3900);
DISPLAY 0.978723 (-2025 3900);
PAINT WHITE (-2025 3900);
DISPLAY INVISIBLE (-2025 3900);
FORCEADD CAP..1
(-2250 2750);
FORCEPROP 1 LAST PART_NUMBER A36096-050
J 0
(-2575 2675);
DISPLAY 0.617021 (-2575 2675);
PAINT BLUE (-2575 2675);
FORCEPROP 1 LAST PACK_TYPE 0402LF
J 0
(-2575 2625);
DISPLAY 0.617021 (-2575 2625);
PAINT SKYBLUE (-2575 2625);
FORCEPROP 1 LAST VOLTAGE 50V
J 0
(-2575 2725);
DISPLAY 0.617021 (-2575 2725);
PAINT SKYBLUE (-2575 2725);
FORCEPROP 1 LAST MATERIAL X7R
J 0
(-2450 2725);
DISPLAY 0.617021 (-2450 2725);
PAINT SKYBLUE (-2450 2725);
FORCEPROP 1 LAST TOLERANCE 10%
J 0
(-2400 2775);
DISPLAY 0.617021 (-2400 2775);
PAINT SKYBLUE (-2400 2775);
FORCEPROP 1 LASTPIN (-2250 2650) $PN 2
J 0
(-2240 2630);
DISPLAY 0.617021 (-2240 2630);
PAINT ORANGE (-2240 2630);
FORCEPROP 1 LAST LOCATION C4W1
J 0
(-2575 2825);
DISPLAY 0.617021 (-2575 2825);
PAINT AQUA (-2575 2825);
FORCEPROP 1 LAST VALUE 220PF
J 0
(-2575 2775);
DISPLAY 0.617021 (-2575 2775);
PAINT SKYBLUE (-2575 2775);
FORCEPROP 1 LASTPIN (-2250 2850) $PN 1
J 0
(-2240 2830);
DISPLAY 0.617021 (-2240 2830);
PAINT ORANGE (-2240 2830);
FORCEPROP 2 LAST CDS_LOCATION C4W1
J 0
(-2200 2850);
DISPLAY 0.617021 (-2200 2850);
PAINT AQUA (-2200 2850);
DISPLAY INVISIBLE (-2200 2850);
FORCEPROP 1 LAST PATH I97
J 0
(-2200 2900);
DISPLAY 0.978723 (-2200 2900);
PAINT WHITE (-2200 2900);
DISPLAY INVISIBLE (-2200 2900);
FORCEPROP 0 LAST CDS_SEC 1
J 0
(-2200 2900);
PAINT MONO (-2200 2900);
DISPLAY INVISIBLE (-2200 2900);
FORCEPROP 2 LAST CDS_LIB mstr_discrete
J 0
(-2250 2750);
PAINT ORANGE (-2250 2750);
DISPLAY INVISIBLE (-2250 2750);
FORCEPROP 2 LAST ROOM PVCCIN_CPU0_VR
J 0
(-2200 2900);
DISPLAY 1.361702 (-2200 2900);
PAINT ORANGE (-2200 2900);
DISPLAY INVISIBLE (-2200 2900);
FORCEPROP 2 LAST SEC 1
J 0
(-2200 2950);
DISPLAY 0.680851 (-2200 2950);
PAINT MONO (-2200 2950);
DISPLAY INVISIBLE (-2200 2950);
FORCEPROP 2 LAST SEC_TYPE 0402LF
J 0
(-2200 2950);
DISPLAY 1.021277 (-2200 2950);
PAINT ORANGE (-2200 2950);
DISPLAY INVISIBLE (-2200 2950);
FORCEADD GND..1
(-2250 2550);
FORCEPROP 3 LASTPIN (-2250 2600) SIG_NAME GND\g
J 0
(-2240 2610);
DISPLAY 0.659574 (-2240 2610);
PAINT MONO (-2240 2610);
DISPLAY INVISIBLE (-2240 2610);
FORCEPROP 1 LAST PATH I98
J 0
(-2175 2550);
DISPLAY 0.872340 (-2175 2550);
PAINT AQUA (-2175 2550);
DISPLAY INVISIBLE (-2175 2550);
FORCEPROP 1 LAST HDL_POWER GND
J 0
(-2250 2700);
DISPLAY 1.170213 (-2250 2700);
PAINT GREEN (-2250 2700);
DISPLAY INVISIBLE (-2250 2700);
FORCEPROP 1 LAST BODY_TYPE PLUMBING
J 0
(-2295 2507);
DISPLAY 0.340426 (-2295 2507);
PAINT GREEN (-2295 2507);
DISPLAY INVISIBLE (-2295 2507);
FORCEPROP 2 LAST CDS_LIB mstr_symbols
J 0
(-2250 2550);
PAINT ORANGE (-2250 2550);
DISPLAY INVISIBLE (-2250 2550);
FORCEPROP 1 LAST VOLTAGE 0
J 0
(-2250 2550);
PAINT SKYBLUE (-2250 2550);
DISPLAY INVISIBLE (-2250 2550);
FORCEPROP 2 LAST ROOM PVCCIN_CPU0_VR
J 0
(-2825 2625);
DISPLAY 1.361702 (-2825 2625);
PAINT ORANGE (-2825 2625);
DISPLAY INVISIBLE (-2825 2625);
FORCEPROP 1 LAST SIZE 1B
J 0
(-2175 2500);
DISPLAY 1.170213 (-2175 2500);
PAINT AQUA (-2175 2500);
DISPLAY INVISIBLE (-2175 2500);
FORCEADD RES..2
(-2125 4525);
FORCEPROP 1 LAST WATTAGE 1/16W
J 0
(-2085 4500);
DISPLAY 0.617021 (-2085 4500);
PAINT SKYBLUE (-2085 4500);
FORCEPROP 1 LAST LOCATION R3P17
J 0
(-2080 4650);
DISPLAY 0.617021 (-2080 4650);
PAINT AQUA (-2080 4650);
FORCEPROP 1 LAST TOLERANCE 1%
J 0
(-2080 4550);
DISPLAY 0.617021 (-2080 4550);
PAINT SKYBLUE (-2080 4550);
FORCEPROP 1 LASTPIN (-2125 4625) $PN 1
J 0
(-2120 4587);
DISPLAY 0.617021 (-2120 4587);
PAINT ORANGE (-2120 4587);
FORCEPROP 1 LASTPIN (-2125 4425) $PN 2
J 0
(-2120 4435);
DISPLAY 0.617021 (-2120 4435);
PAINT ORANGE (-2120 4435);
FORCEPROP 1 LAST MATERIAL CHIP
J 0
(-2085 4450);
DISPLAY 0.617021 (-2085 4450);
PAINT SKYBLUE (-2085 4450);
FORCEPROP 1 LAST PART_NUMBER G21796-047
J 0
(-2085 4400);
DISPLAY 0.617021 (-2085 4400);
PAINT BLUE (-2085 4400);
FORCEPROP 1 LAST VALUE 49.9
J 0
(-2080 4600);
DISPLAY 0.617021 (-2080 4600);
PAINT SKYBLUE (-2080 4600);
FORCEPROP 1 LAST PACK_TYPE 0402
J 0
(-2085 4350);
DISPLAY 0.617021 (-2085 4350);
PAINT SKYBLUE (-2085 4350);
FORCEPROP 1 LAST PATH I99
J 0
(-2075 4700);
DISPLAY 0.978723 (-2075 4700);
PAINT WHITE (-2075 4700);
DISPLAY INVISIBLE (-2075 4700);
FORCEPROP 0 LAST CDS_SEC 1
J 0
(-2075 4700);
PAINT MONO (-2075 4700);
DISPLAY INVISIBLE (-2075 4700);
FORCEPROP 2 LAST CDS_LIB mstr_discrete
J 0
(-2125 4525);
PAINT ORANGE (-2125 4525);
DISPLAY INVISIBLE (-2125 4525);
FORCEPROP 2 LAST SEC_TYPE 0402
J 0
(-2075 4750);
DISPLAY 1.021277 (-2075 4750);
PAINT ORANGE (-2075 4750);
DISPLAY INVISIBLE (-2075 4750);
FORCEPROP 2 LAST SEC 1
J 0
(-2075 4750);
DISPLAY 0.680851 (-2075 4750);
PAINT MONO (-2075 4750);
DISPLAY INVISIBLE (-2075 4750);
FORCEPROP 2 LAST ROOM PVCCIN_CPU0_VR
J 0
(-2075 4700);
DISPLAY 1.361702 (-2075 4700);
PAINT ORANGE (-2075 4700);
DISPLAY INVISIBLE (-2075 4700);
FORCEPROP 2 LAST CDS_LOCATION R3P17
J 0
(-2080 4650);
DISPLAY 0.617021 (-2080 4650);
PAINT AQUA (-2080 4650);
DISPLAY INVISIBLE (-2080 4650);
FORCEADD DESIGN_NOTE..1
(-300 1750);
FORCEPROP 0 LAST L1 SMBUS ADDRESS: 0X94
J 0
(-500 1625);
DISPLAY 1.021277 (-500 1625);
PAINT VIOLET (-500 1625);
FORCEPROP 1 LAST COMMENT_BODY TRUE
J 0
(-275 1850);
DISPLAY 0.978723 (-275 1850);
PAINT ORANGE (-275 1850);
DISPLAY INVISIBLE (-275 1850);
FORCEPROP 2 LAST CDS_LIB mstr_symbols
J 0
(-300 1750);
PAINT ORANGE (-300 1750);
DISPLAY INVISIBLE (-300 1750);
FORCEADD DNS..2
(1530 4095);
PAINT RED (1530 4095);
FORCEPROP 1 LAST COMMENT_BODY TRUE
R 1
J 0
(1605 3870);
DISPLAY 0.872340 (1605 3870);
PAINT GREEN (1605 3870);
DISPLAY INVISIBLE (1605 3870);
FORCEPROP 2 LAST CDS_LIB mstr_misc
J 0
(1530 4095);
PAINT ORANGE (1530 4095);
DISPLAY INVISIBLE (1530 4095);
FORCEADD DNS..2
(-1120 4295);
PAINT RED (-1120 4295);
FORCEPROP 1 LAST COMMENT_BODY TRUE
R 1
J 0
(-1045 4070);
DISPLAY 0.872340 (-1045 4070);
PAINT GREEN (-1045 4070);
DISPLAY INVISIBLE (-1045 4070);
FORCEPROP 2 LAST CDS_LIB mstr_misc
J 0
(-1120 4295);
PAINT ORANGE (-1120 4295);
DISPLAY INVISIBLE (-1120 4295);
FORCEADD INTEL_CORP_BPAGE..1
(4250 200);
FORCEPROP 1 LAST CDS_CON_LAST_MODIFIED Fri Jun 16 17:49:16 2017
J 0
(2825 525);
PAINT ORANGE (2825 525);
DISPLAY INVISIBLE (2825 525);
FORCEPROP 1 LAST CUSTOM_TXT_CDS <CURRENT_DESIGN_SHEET> OF <TOTAL_DESIGN_SHEETS>
J 0
(3750 225);
PAINT ORANGE (3750 225);
FORCEPROP 1 LAST CUSTOM_TXT_CDS <CON_LAST_MODIFIED>
J 0
(250 300);
PAINT ORANGE (250 300);
FORCEPROP 2 LAST CUSTOM_TXT_CDS <XR_PAGE_TITLE>
J 0
(-3640 5450);
DISPLAY 0.638298 (-3640 5450);
PAINT PINK (-3640 5450);
DISPLAY INVISIBLE (-3640 5450);
FORCEPROP 1 LAST SCH_TITLE PVCCIO CPU0 (1 OF 2)
J 0
(-3700 250);
DISPLAY 1.212766 (-3700 250);
PAINT ORANGE (-3700 250);
FORCEPROP 1 LAST COMMENT_BODY TRUE
J 0
(4262 212);
DISPLAY 0.468085 (4262 212);
PAINT GREEN (4262 212);
DISPLAY INVISIBLE (4262 212);
FORCEPROP 2 LAST CDS_LIB mstr_symbols
J 0
(4250 200);
PAINT MONO (4250 200);
DISPLAY INVISIBLE (4250 200);
FORCEPROP 2 LAST PAGE_BORDER TRUE
J 0
(-3640 5450);
DISPLAY 0.638298 (-3640 5450);
PAINT PINK (-3640 5450);
DISPLAY INVISIBLE (-3640 5450);
FORCEPROP 2 LAST CDS_XR_PAGE_TITLE CR-211 : @BASEBOARD_FAB2_LIB.BASEBOARD_FAB2(SCH_1):PAGE211
J 0
(-3640 5450);
DISPLAY 0.638298 (-3640 5450);
PAINT PINK (-3640 5450);
DISPLAY INVISIBLE (-3640 5450);
FORCEADD DESIGN_NOTE..1
(2775 5050);
FORCEPROP 0 LAST L1 SVID ADDRESS
J 0
(2575 4925);
DISPLAY 1.021277 (2575 4925);
PAINT VIOLET (2575 4925);
FORCEPROP 0 LAST L2 PVCCIN_CPU0: 0X02(BUS #1)
J 0
(2575 4850);
DISPLAY 1.021277 (2575 4850);
PAINT VIOLET (2575 4850);
FORCEPROP 1 LAST COMMENT_BODY TRUE
J 0
(2800 5150);
DISPLAY 0.978723 (2800 5150);
PAINT ORANGE (2800 5150);
DISPLAY INVISIBLE (2800 5150);
FORCEPROP 2 LAST CDS_LIB mstr_symbols
J 0
(2775 5050);
PAINT ORANGE (2775 5050);
DISPLAY INVISIBLE (2775 5050);
WIRE 16 -1 (2475 1150)(2475 1325);
WIRE 16 -1 (2075 1275)(2075 1325);
WIRE 16 -1 (-1600 4600)(-1600 4775);
WIRE 16 -1 (925 2100)(925 1950);
WIRE 16 -1 (925 2150)(925 2100);
WIRE 16 -1 (550 2100)(925 2100);
WIRE 16 -1 (925 2300)(925 2150);
WIRE 16 -1 (550 2150)(925 2150);
WIRE 16 -1 (550 2300)(925 2300);
WIRE 16 -1 (75 4025)(75 4075);
WIRE 16 -1 (-325 4025)(-325 4075);
WIRE 16 -1 (-625 4725)(-625 4800);
WIRE 16 -1 (-1125 4725)(-625 4725);
WIRE 16 -1 (-625 4625)(-625 4725);
WIRE 16 -1 (-1125 4400)(-1125 4725);
WIRE 16 -1 (-2125 4625)(-2125 4825);
WIRE 16 -1 (-2500 4750)(-2500 4800);
WIRE 16 -1 (-2500 4150)(-2500 4200);
WIRE 16 -1 (-2850 4150)(-2850 4200);
WIRE 16 -1 (-1025 2100)(-1025 2150);
WIRE 16 -1 (-350 2150)(-1025 2150);
WIRE 16 -1 (-925 850)(-925 800);
WIRE 16 -1 (-575 850)(-925 850);
WIRE 16 -1 (-925 1100)(-925 850);
WIRE 16 -1 (-575 1100)(-575 850);
WIRE 16 -1 (1800 4525)(1800 4725);
WIRE 16 -1 (1525 4525)(1800 4525);
WIRE 16 -1 (1800 4525)(2075 4525);
WIRE 16 -1 (2075 4525)(2075 4150);
WIRE 16 -1 (775 4525)(1525 4525);
WIRE 16 -1 (1525 4200)(1525 4525);
WIRE 16 -1 (775 4200)(775 4525);
WIRE 16 -1 (1650 2650)(1650 2525);
WIRE 16 -1 (-2250 2600)(-2250 2650);
WIRE 3 2175 (-2850 3875)(-2300 3875);
WIRE 3 2175 (-2300 3650)(-2300 3875);
WIRE 3 2175 (-2850 3650)(-2850 3875);
WIRE 3 2175 (-2850 3650)(-2300 3650);
WIRE 3 2175 (-3725 3575)(-3725 3900);
WIRE 3 2175 (-3725 3900)(-3150 3900);
WIRE 3 2175 (-3725 3575)(-3150 3575);
WIRE 3 2175 (-3150 3575)(-3150 3900);
WIRE 16 -1 (-2975 3975)(-2125 3975);
FORCEPROP 0 LAST SIG_NAME SVID_CLK0_CPU0_R
J 0
(-2925 3985);
DISPLAY 0.617021 (-2925 3985);
PAINT ORANGE (-2925 3985);
WIRE 16 -1 (-2075 3975)(-2125 3975);
WIRE 16 -1 (-2125 4425)(-2125 3975);
WIRE 16 -1 (-2700 2950)(-1600 2950);
FORCEPROP 2 LAST SIG_NAME SVID_DIO0_CPU0_R
J 0
(-2675 2960);
DISPLAY 0.617021 (-2675 2960);
PAINT ORANGE (-2675 2960);
WIRE 16 -1 (-1350 2950)(-1600 2950);
WIRE 16 -1 (-1600 4400)(-1600 2950);
WIRE 16 -1 (-2150 3450)(-2700 3450);
FORCEPROP 2 LAST SIG_NAME VR_PVCCIO_CPU0_AIREF1
J 0
(-2700 3465);
DISPLAY 0.617021 (-2700 3465);
PAINT ORANGE (-2700 3465);
WIRE 16 -1 (-350 3450)(-2150 3450);
WIRE 16 -1 (-2150 3600)(-2150 3450);
WIRE 16 -1 (-2050 3600)(-2150 3600);
WIRE 16 -1 (-2150 3750)(-2150 3600);
WIRE 16 -1 (-2150 3750)(-2075 3750);
WIRE 3 2175 (-2250 3900)(-1250 3900);
WIRE 3 2175 (-1250 3500)(-1250 3900);
WIRE 3 2175 (-2250 3500)(-2250 3900);
WIRE 3 2175 (-2250 3500)(-1250 3500);
WIRE 16 -1 (-575 2050)(-350 2050);
WIRE 16 -1 (-575 1300)(-575 2050);
FORCEPROP 0 LAST VOLTAGE 3.3V
J 0
(-575 1350);
DISPLAY 1.021277 (-575 1350);
PAINT SKYBLUE (-575 1350);
DISPLAY INVISIBLE (-575 1350);
FORCEPROP 0 LAST SIG_NAME VR_PVCCIO_CPU0_XADDR2
R 1
J 0
(-585 1435);
DISPLAY 0.617021 (-585 1435);
PAINT ORANGE (-585 1435);
FORCEPROP 2 LASTPROP $XRERR UNIQUE?
J 0
(-825 1435);
DISPLAY 0.638298 (-825 1435);
PAINT MONO (-825 1435);
DISPLAY INVISIBLE (-825 1435);
WIRE 3 682 (-2200 4700)(-2200 4300);
WIRE 3 682 (-1300 4700)(-2200 4700);
WIRE 3 682 (-2200 4300)(-1300 4300);
WIRE 3 682 (-1300 4300)(-1300 4700);
WIRE 16 -1 (-350 3550)(-925 3550);
WIRE 16 -1 (-925 3550)(-925 3975);
WIRE 16 -1 (-1875 3975)(-925 3975);
FORCEPROP 2 LAST SIG_NAME SVID_CLK_PVCCIO_CPU0
J 0
(-1615 3990);
DISPLAY 0.617021 (-1615 3990);
PAINT ORANGE (-1615 3990);
FORCEPROP 2 LASTPROP $XRERR UNIQUE?
J 0
(-1855 3990);
DISPLAY 0.638298 (-1855 3990);
PAINT MONO (-1855 3990);
DISPLAY INVISIBLE (-1855 3990);
WIRE 16 -1 (-1125 3250)(-350 3250);
WIRE 16 -1 (-1125 4200)(-1125 3250);
WIRE 16 -1 (-1850 3250)(-1125 3250);
FORCEPROP 2 LAST SIG_NAME VR_PVCCIO_CPU0_EN
J 0
(-1525 3265);
DISPLAY 0.617021 (-1525 3265);
PAINT ORANGE (-1525 3265);
FORCEPROP 2 LASTPROP $XRERR UNIQUE?
J 0
(-1765 3265);
DISPLAY 0.638298 (-1765 3265);
PAINT MONO (-1765 3265);
DISPLAY INVISIBLE (-1765 3265);
WIRE 16 -1 (-1875 3750)(-1650 3750);
WIRE 16 -1 (-1900 3600)(-1650 3600);
WIRE 16 -1 (-1650 3750)(-1650 3600);
WIRE 16 -1 (-1650 3600)(-1650 3400);
WIRE 16 -1 (-1650 3400)(-350 3400);
WIRE 16 -1 (-2700 3400)(-1650 3400);
FORCEPROP 2 LAST SIG_NAME ISENSE_PVCCIO_CPU0_PH1_IMON
J 2
(-2079 3400);
DISPLAY 0.617021 (-2079 3400);
PAINT ORANGE (-2079 3400);
WIRE 16 -1 (1275 3150)(550 3150);
FORCEPROP 2 LAST SIG_NAME SVID_ALERT_PVCCIO_CPU0
J 0
(650 3165);
DISPLAY 0.617021 (650 3165);
PAINT ORANGE (650 3165);
FORCEPROP 2 LASTPROP $XRERR UNIQUE?
J 0
(410 3165);
DISPLAY 0.638298 (410 3165);
PAINT MONO (410 3165);
DISPLAY INVISIBLE (410 3165);
WIRE 16 -1 (2075 3250)(2075 3950);
WIRE 16 -1 (550 3250)(2075 3250);
FORCEPROP 2 LAST SIG_NAME IRQ_PVCCIO_CPU0_VRHOT_N
J 0
(650 3265);
DISPLAY 0.617021 (650 3265);
PAINT ORANGE (650 3265);
FORCEPROP 2 LASTPROP $XRERR UNIQUE?
J 0
(410 3265);
DISPLAY 0.638298 (410 3265);
PAINT MONO (410 3265);
DISPLAY INVISIBLE (410 3265);
WIRE 16 -1 (-2250 3300)(-2250 2850);
WIRE 16 -1 (-2250 3300)(-350 3300);
FORCEPROP 2 LAST SIG_NAME A_TSENSE_PVCCIO_CPU0
J 2
(-2233 3316);
DISPLAY 0.617021 (-2233 3316);
PAINT ORANGE (-2233 3316);
WIRE 16 -1 (-2700 3300)(-2250 3300);
FORCEPROP 0 LAST VOLTAGE 3.6
J 0
(-2725 3375);
DISPLAY 1.021277 (-2725 3375);
PAINT SKYBLUE (-2725 3375);
DISPLAY INVISIBLE (-2725 3375);
WIRE 16 -1 (-350 3150)(-2700 3150);
FORCEPROP 2 LAST SIG_NAME VR_PVCCIO_CPU0_VINSEN
J 0
(-2725 3165);
DISPLAY 0.617021 (-2725 3165);
PAINT ORANGE (-2725 3165);
WIRE 16 -1 (-350 3000)(-2700 3000);
FORCEPROP 2 LAST SIG_NAME VR_PVCCIO_CPU0_VD12
J 0
(-2700 3015);
DISPLAY 0.617021 (-2700 3015);
PAINT ORANGE (-2700 3015);
WIRE 16 -1 (-2400 1950)(-2400 2050);
WIRE 16 -1 (-2500 2050)(-2400 2050);
FORCEPROP 2 LAST SIG_NAME VR_PVCCIO_CPU0_AVSP
J 0
(-2065 2715);
DISPLAY 0.617021 (-2065 2715);
PAINT ORANGE (-2065 2715);
FORCEPROP 2 LASTPROP $XRERR UNIQUE?
J 0
(-2305 2715);
DISPLAY 0.638298 (-2305 2715);
PAINT MONO (-2305 2715);
DISPLAY INVISIBLE (-2305 2715);
WIRE 16 -1 (-2400 2050)(-2125 2050);
WIRE 16 -1 (-2125 2050)(-2125 2700);
WIRE 16 -1 (-350 2700)(-2125 2700);
FORCEPROP 0 LAST VOLTAGE 2
J 0
(-1300 2750);
DISPLAY 1.021277 (-1300 2750);
PAINT SKYBLUE (-1300 2750);
DISPLAY INVISIBLE (-1300 2750);
WIRE 3 682 (-2600 2900)(-2150 2900);
WIRE 3 682 (-2150 2900)(-2150 2525);
WIRE 3 682 (-2600 2525)(-2600 2900);
WIRE 3 682 (-2600 2525)(-2150 2525);
WIRE 3 682 (-2950 4100)(-2950 4600);
WIRE 3 682 (-2550 4600)(-2950 4600);
WIRE 3 682 (-2950 4100)(-2550 4100);
WIRE 3 682 (-2550 4100)(-2550 4600);
WIRE 16 -1 (-2500 4400)(-2500 4500);
WIRE 16 -1 (-2500 4500)(-2500 4550);
WIRE 16 -1 (-2850 4400)(-2850 4500);
WIRE 16 -1 (-2500 4500)(-2850 4500);
FORCEPROP 0 LAST VOLTAGE 0.8
J 0
(-2600 4550);
DISPLAY 1.021277 (-2600 4550);
PAINT SKYBLUE (-2600 4550);
DISPLAY INVISIBLE (-2600 4550);
WIRE 16 -1 (-2850 4700)(-3275 4700);
FORCEPROP 2 LAST SIG_NAME VR_PVCCIO_CPU0_VINSEN
J 0
(-3290 4715);
DISPLAY 0.617021 (-3290 4715);
PAINT ORANGE (-3290 4715);
WIRE 16 -1 (-2850 4700)(-2850 4500);
WIRE 16 -1 (-1150 2950)(-350 2950);
FORCEPROP 2 LAST SIG_NAME SVID_VDIO_PVCCIO_CPU0
J 0
(-1050 2965);
DISPLAY 0.617021 (-1050 2965);
PAINT ORANGE (-1050 2965);
FORCEPROP 2 LASTPROP $XRERR UNIQUE?
J 0
(-1290 2965);
DISPLAY 0.638298 (-1290 2965);
PAINT MONO (-1290 2965);
DISPLAY INVISIBLE (-1290 2965);
WIRE 16 -1 (1975 3600)(2650 3600);
FORCEPROP 2 LAST SIG_NAME PWRGD_PVCCIO_CPU0
J 0
(2175 3615);
DISPLAY 0.617021 (2175 3615);
PAINT ORANGE (2175 3615);
WIRE 16 -1 (1475 3150)(2650 3150);
FORCEPROP 2 LAST SIG_NAME SVID_ALERT0_CPU0_R_N
J 0
(2075 3160);
DISPLAY 0.617021 (2075 3160);
PAINT ORANGE (2075 3160);
WIRE 16 -1 (2650 3000)(550 3000);
FORCEPROP 0 LAST VOLTAGE 3.3
J 0
(2075 3075);
DISPLAY 1.021277 (2075 3075);
PAINT SKYBLUE (2075 3075);
DISPLAY INVISIBLE (2075 3075);
FORCEPROP 2 LAST SIG_NAME VR_PVCCIO_CPU0_PWM1
J 0
(2075 3015);
DISPLAY 0.617021 (2075 3015);
PAINT ORANGE (2075 3015);
WIRE 16 -1 (1525 4000)(1525 2900);
WIRE 16 -1 (550 2900)(1525 2900);
FORCEPROP 2 LAST SIG_NAME PU_VR_PVCCIO_CPU0_FAULT1
J 0
(650 2915);
DISPLAY 0.617021 (650 2915);
PAINT ORANGE (650 2915);
FORCEPROP 2 LASTPROP $XRERR UNIQUE?
J 0
(410 2915);
DISPLAY 0.638298 (410 2915);
PAINT MONO (410 2915);
DISPLAY INVISIBLE (410 2915);
WIRE 16 -1 (550 3600)(775 3600);
WIRE 16 -1 (775 4000)(775 3600);
WIRE 16 -1 (1650 3600)(775 3600);
FORCEPROP 2 LAST SIG_NAME PWRGD_PVCCIO_CPU0_R
J 0
(910 3615);
DISPLAY 0.617021 (910 3615);
PAINT ORANGE (910 3615);
FORCEPROP 2 LASTPROP $XRERR UNIQUE?
J 0
(670 3615);
DISPLAY 0.638298 (670 3615);
PAINT MONO (670 3615);
DISPLAY INVISIBLE (670 3615);
WIRE 16 -1 (1650 3600)(1775 3600);
WIRE 16 -1 (1650 2850)(1650 3600);
WIRE 3 682 (-250 1000)(-650 1000);
WIRE 3 682 (-250 1400)(-250 1000);
WIRE 3 682 (-650 1000)(-650 1400);
WIRE 3 682 (-650 1400)(-250 1400);
WIRE 16 -1 (-925 2100)(-350 2100);
FORCEPROP 0 LAST VOLTAGE 3.3
J 0
(-625 2150);
DISPLAY 1.021277 (-625 2150);
PAINT SKYBLUE (-625 2150);
DISPLAY INVISIBLE (-625 2150);
WIRE 16 -1 (-925 1300)(-925 2100);
FORCEPROP 0 LAST SIG_NAME VR_PVCCIO_CPU0_XADDR1
R 1
J 0
(-935 1435);
DISPLAY 0.617021 (-935 1435);
PAINT ORANGE (-935 1435);
FORCEPROP 2 LASTPROP $XRERR UNIQUE?
J 0
(-1175 1435);
DISPLAY 0.638298 (-1175 1435);
PAINT MONO (-1175 1435);
DISPLAY INVISIBLE (-1175 1435);
WIRE 3 682 (700 2400)(650 2400);
WIRE 3 682 (700 2550)(700 2400);
WIRE 3 682 (700 2550)(750 2550);
WIRE 3 682 (700 2600)(700 2550);
WIRE 3 682 (650 2600)(700 2600);
WIRE 16 -1 (-350 2650)(-2050 2650);
WIRE 16 -1 (-2050 1650)(-2050 2650);
WIRE 16 -1 (-2400 1750)(-2400 1650);
WIRE 16 -1 (-2400 1650)(-2050 1650);
WIRE 16 -1 (-3300 1650)(-2400 1650);
FORCEPROP 2 LAST SIG_NAME VSENSE_PVCCIO_CPU0_AVSN
J 0
(-3315 1665);
DISPLAY 0.617021 (-3315 1665);
PAINT ORANGE (-3315 1665);
WIRE 16 -1 (-350 2450)(-2700 2450);
FORCEPROP 2 LAST SIG_NAME SMB_VR_STBY_LVC3_SDA
J 0
(-2725 2465);
DISPLAY 0.617021 (-2725 2465);
PAINT ORANGE (-2725 2465);
WIRE 16 -1 (-350 2400)(-2700 2400);
FORCEPROP 2 LAST SIG_NAME SMB_VR_STBY_LVC3_SCL
J 0
(-2725 2415);
DISPLAY 0.617021 (-2725 2415);
PAINT ORANGE (-2725 2415);
WIRE 3 682 (-450 2200)(-400 2200);
WIRE 3 682 (-450 2300)(-450 2200);
WIRE 3 682 (-400 2300)(-450 2300);
WIRE 3 682 (-1550 2500)(-1550 2350);
WIRE 3 682 (-1300 2500)(-1550 2500);
WIRE 3 682 (-1550 2350)(-1300 2350);
WIRE 3 682 (-1300 2350)(-1300 2500);
WIRE 3 682 (700 2700)(650 2700);
WIRE 3 682 (700 2800)(750 2800);
WIRE 3 682 (700 2800)(700 2700);
WIRE 3 682 (700 2850)(700 2800);
WIRE 3 682 (650 2850)(700 2850);
WIRE 3 682 (-450 2550)(-400 2550);
WIRE 3 682 (-450 2600)(-450 2550);
WIRE 3 682 (-400 2600)(-450 2600);
WIRE 16 -1 (2075 1525)(2075 1600);
WIRE 16 -1 (2475 1525)(2475 1600);
WIRE 16 -1 (2475 1600)(2075 1600);
FORCEPROP 2 LAST SIG_NAME VR_PVCCIO_CPU0_VD12
J 0
(2160 1615);
DISPLAY 0.617021 (2160 1615);
PAINT ORANGE (2160 1615);
WIRE 16 -1 (2475 1600)(2975 1600);
WIRE 16 -1 (-2700 2050)(-3375 2050);
FORCEPROP 2 LAST SIG_NAME VSENSE_PVCCIO_CPU0_AVSP
J 0
(-3365 2065);
DISPLAY 0.617021 (-3365 2065);
PAINT ORANGE (-3365 2065);
WIRE 16 -1 (-2700 3250)(-2050 3250);
FORCEPROP 2 LAST SIG_NAME FM_PVCCIO_CPU0_EN
J 0
(-2700 3265);
DISPLAY 0.617021 (-2700 3265);
PAINT ORANGE (-2700 3265);
WIRE 16 -1 (75 4275)(75 4325);
WIRE 16 -1 (-325 4275)(-325 4325);
WIRE 16 -1 (75 4325)(-325 4325);
WIRE 16 -1 (-625 4325)(-625 4425);
WIRE 16 -1 (-325 4325)(-625 4325);
WIRE 16 -1 (-625 3600)(-625 4325);
FORCEPROP 2 LAST SIG_NAME VR_PVCCIO_CPU0_VDD
R 1
J 0
(-640 3715);
DISPLAY 0.617021 (-640 3715);
PAINT ORANGE (-640 3715);
FORCEPROP 2 LASTPROP $XRERR UNIQUE?
J 0
(-880 3715);
DISPLAY 0.638298 (-880 3715);
PAINT MONO (-880 3715);
DISPLAY INVISIBLE (-880 3715);
WIRE 16 -1 (-350 3600)(-625 3600);
DOT 1 (-1650 3600);
DOT 1 (-925 850);
DOT 1 (-1125 3250);
DOT 1 (925 2150);
DOT 1 (-1600 2950);
DOT 1 (-2400 1650);
DOT 1 (-1650 3400);
DOT 1 (-2150 3450);
DOT 1 (-2125 3975);
DOT 1 (-625 4325);
DOT 1 (-625 4725);
DOT 1 (-325 4325);
DOT 1 (775 3600);
DOT 1 (1650 3600);
DOT 1 (2475 1600);
DOT 1 (1525 4525);
DOT 1 (1800 4525);
DOT 1 (-2150 3600);
DOT 1 (-2400 2050);
DOT 1 (-2250 3300);
DOT 1 (700 2550);
DOT 1 (700 2800);
DOT 1 (925 2100);
DOT 1 (-2850 4500);
DOT 1 (-2500 4500);
FORCENOTE
TP FAB1 NC 0321
(650 3450) 0;
DISPLAY LEFT (650 3450);
DISPLAY 1.021277 (650 3450);
PAINT RED (650 3450);
FORCENOTE
TP FAB1 DELETE RES 0203
(-2925 3600) 0;
DISPLAY LEFT (-2925 3600);
DISPLAY 0.808511 (-2925 3600);
PAINT RED (-2925 3600);
FORCENOTE
INFINEON:NOPOP
(-3700 3700) 0;
DISPLAY LEFT (-3700 3700);
DISPLAY 0.872340 (-3700 3700);
PAINT RED (-3700 3700);
FORCENOTE
RF13 & CF13
(-3700 3800) 0;
DISPLAY LEFT (-3700 3800);
DISPLAY 0.872340 (-3700 3800);
PAINT RED (-3700 3800);
FORCENOTE
FAIRCHILD:POP
(-3700 3600) 0;
DISPLAY LEFT (-3700 3600);
DISPLAY 0.872340 (-3700 3600);
PAINT RED (-3700 3600);
FORCENOTE
TP FAB1 CO-LAY WITH FAIRCHILD PARTS 1203
(-2737 3906) 0;
DISPLAY LEFT (-2737 3906);
DISPLAY 1.021277 (-2737 3906);
PAINT RED (-2737 3906);
FORCENOTE
TP FAB1 ADD CAP 0218
(-2125 2750) 0;
DISPLAY LEFT (-2125 2750);
DISPLAY 1.021277 (-2125 2750);
PAINT RED (-2125 2750);
FORCENOTE
TP FAB1 NC 0321
(-1100 2800) 0;
DISPLAY LEFT (-1100 2800);
DISPLAY 1.021277 (-1100 2800);
PAINT RED (-1100 2800);
FORCENOTE
TP FAB1 CHANGE RES 0408
(-500 950) 0;
DISPLAY LEFT (-500 950);
DISPLAY 0.638298 (-500 950);
PAINT RED (-500 950);
FORCENOTE
TP FAB3 CHANGE RES 0804
(-500 900) 0;
DISPLAY LEFT (-500 900);
DISPLAY 0.638298 (-500 900);
PAINT RED (-500 900);
FORCENOTE
TP FAB1 NC 0321
(800 2775) 0;
DISPLAY LEFT (800 2775);
DISPLAY 1.021277 (800 2775);
PAINT RED (800 2775);
FORCENOTE
TP FAB1 NC 0321
(600 3050) 0;
DISPLAY LEFT (600 3050);
DISPLAY 1.021277 (600 3050);
PAINT RED (600 3050);
FORCENOTE
ROOM = PVCCIO_CPU0
(-3550 425) 0;
DISPLAY LEFT (-3550 425);
DISPLAY 1.021277 (-3550 425);
PAINT PURPLE (-3550 425);
FORCENOTE
BOM_COST = PROC_VRD_PVCCIO_CPU0
(-3550 350) 0;
DISPLAY LEFT (-3550 350);
DISPLAY 1.021277 (-3550 350);
PAINT PURPLE (-3550 350);
FORCENOTE
TP FAB1 DEL RES 0314
(-1950 2525) 0;
DISPLAY LEFT (-1950 2525);
DISPLAY 1.021277 (-1950 2525);
PAINT RED (-1950 2525);
FORCENOTE
TP FAB1 NC 0321
(-1100 2275) 0;
DISPLAY LEFT (-1100 2275);
DISPLAY 1.021277 (-1100 2275);
PAINT RED (-1100 2275);
FORCENOTE
TP FAB1 NC 0321
(-1100 2550) 0;
DISPLAY LEFT (-1100 2550);
DISPLAY 1.021277 (-1100 2550);
PAINT RED (-1100 2550);
FORCENOTE
TP FAB1 DEL NETS 0309
(775 2525) 0;
DISPLAY LEFT (775 2525);
DISPLAY 1.021277 (775 2525);
PAINT RED (775 2525);
FORCENOTE
TP FAB1 POP RES 0316
(-2100 4725) 0;
DISPLAY LEFT (-2100 4725);
DISPLAY 1.021277 (-2100 4725);
PAINT RED (-2100 4725);
FORCENOTE
TP FAB3 CHANGE CAP 0912
(-2950 4050) 0;
DISPLAY LEFT (-2950 4050);
DISPLAY 0.638298 (-2950 4050);
PAINT RED (-2950 4050);
FORCENOTE
TP FAB1 NC 0321
(-1100 3075) 0;
DISPLAY LEFT (-1100 3075);
DISPLAY 1.021277 (-1100 3075);
PAINT RED (-1100 3075);
QUIT
